FILE_TYPE = MACRO_DRAWING;
SET COLOR_WIRE YELLOW;
SET COLOR_PROP ORANGE;
SET COLOR_DOT WHITE;
SET COLOR_ARC YELLOW;
SET COLOR_BODY GREEN;
SET COLOR_NOTE PURPLE;
SET PROP_DISPLAY VALUE;
SET PAGE_NUMBER P92;
FORCEADD OFFPAGE..5
(-8325 1950);
FORCEPROP 2 LAST $XR0 17 
J 0
(-8549 1950);
DISPLAY 0.638298 (-8549 1950);
PAINT MONO (-8549 1950);
FORCEPROP 2 LAST PATH I1
J 0
(-8275 2025);
DISPLAY 1.021277 (-8275 2025);
DISPLAY INVISIBLE (-8275 2025);
FORCEPROP 1 LAST COMMENT_BODY TRUE
J 0
(-8225 1875);
DISPLAY 0.872340 (-8225 1875);
PAINT GREEN (-8225 1875);
DISPLAY INVISIBLE (-8225 1875);
FORCEPROP 1 LAST OFFPAGE TRUE
J 0
(-8000 1825);
DISPLAY 0.872340 (-8000 1825);
PAINT GREEN (-8000 1825);
DISPLAY INVISIBLE (-8000 1825);
FORCEPROP 2 LAST CDS_LIB mstr_standard
J 0
(-8325 1950);
DISPLAY 0.808511 (-8325 1950);
DISPLAY INVISIBLE (-8325 1950);
FORCEADD OFFPAGE..6
(-8325 3550);
FORCEPROP 2 LAST $XR0 17 
J 0
(-8574 3550);
DISPLAY 0.638298 (-8574 3550);
PAINT MONO (-8574 3550);
FORCEPROP 2 LAST PATH I10
J 0
(-8275 3625);
DISPLAY 1.021277 (-8275 3625);
DISPLAY INVISIBLE (-8275 3625);
FORCEPROP 1 LAST COMMENT_BODY TRUE
J 0
(-8225 3475);
DISPLAY 0.872340 (-8225 3475);
PAINT GREEN (-8225 3475);
DISPLAY INVISIBLE (-8225 3475);
FORCEPROP 1 LAST OFFPAGE TRUE
J 0
(-8000 3425);
DISPLAY 0.872340 (-8000 3425);
PAINT GREEN (-8000 3425);
DISPLAY INVISIBLE (-8000 3425);
FORCEPROP 2 LAST CDS_LIB mstr_standard
J 0
(-8325 3550);
DISPLAY 0.723404 (-8325 3550);
PAINT MONO (-8325 3550);
DISPLAY INVISIBLE (-8325 3550);
FORCEADD TAP..1
(-6025 4150);
FORCEPROP 3 LASTPIN (-6075 4150) SIG_NAME M_H_CPU0_SA_DQ<7>
J 0
(-6065 4160);
DISPLAY 0.659574 (-6065 4160);
PAINT MONO (-6065 4160);
DISPLAY INVISIBLE (-6065 4160);
FORCEPROP 1 LASTPIN (-6075 4150) BN 7
J 0
(-6087 4158);
DISPLAY 0.489362 (-6087 4158);
PAINT GREEN (-6087 4158);
FORCEPROP 2 LAST CDS_LIB mstr_standard
J 0
(-6025 4150);
DISPLAY 0.723404 (-6025 4150);
PAINT MONO (-6025 4150);
DISPLAY INVISIBLE (-6025 4150);
FORCEPROP 1 LAST BODY_TYPE PLUMBING
J 0
(-6025 4200);
DISPLAY 0.872340 (-6025 4200);
PAINT GREEN (-6025 4200);
DISPLAY INVISIBLE (-6025 4200);
FORCEPROP 1 LAST HDL_TAP TRUE
J 0
(-5700 4025);
DISPLAY 0.872340 (-5700 4025);
DISPLAY INVISIBLE (-5700 4025);
FORCEPROP 1 LAST PATH I100
J 0
(-6027 4150);
DISPLAY 0.872340 (-6027 4150);
PAINT GREEN (-6027 4150);
DISPLAY INVISIBLE (-6027 4150);
FORCEADD TAP..1
(-6025 4100);
FORCEPROP 3 LASTPIN (-6075 4100) SIG_NAME M_H_CPU0_SA_DQ<6>
J 0
(-6065 4110);
DISPLAY 0.659574 (-6065 4110);
PAINT MONO (-6065 4110);
DISPLAY INVISIBLE (-6065 4110);
FORCEPROP 1 LASTPIN (-6075 4100) BN 6
J 0
(-6087 4108);
DISPLAY 0.489362 (-6087 4108);
PAINT GREEN (-6087 4108);
FORCEPROP 2 LAST CDS_LIB mstr_standard
J 0
(-6025 4100);
DISPLAY 0.723404 (-6025 4100);
PAINT MONO (-6025 4100);
DISPLAY INVISIBLE (-6025 4100);
FORCEPROP 1 LAST BODY_TYPE PLUMBING
J 0
(-6025 4150);
DISPLAY 0.872340 (-6025 4150);
PAINT GREEN (-6025 4150);
DISPLAY INVISIBLE (-6025 4150);
FORCEPROP 1 LAST HDL_TAP TRUE
J 0
(-5700 3975);
DISPLAY 0.872340 (-5700 3975);
DISPLAY INVISIBLE (-5700 3975);
FORCEPROP 1 LAST PATH I101
J 0
(-6027 4100);
DISPLAY 0.872340 (-6027 4100);
PAINT GREEN (-6027 4100);
DISPLAY INVISIBLE (-6027 4100);
FORCEADD TAP..1
(-6025 4200);
FORCEPROP 3 LASTPIN (-6075 4200) SIG_NAME M_H_CPU0_SA_DQ<8>
J 0
(-6065 4210);
DISPLAY 0.659574 (-6065 4210);
PAINT MONO (-6065 4210);
DISPLAY INVISIBLE (-6065 4210);
FORCEPROP 1 LASTPIN (-6075 4200) BN 8
J 0
(-6087 4208);
DISPLAY 0.489362 (-6087 4208);
PAINT GREEN (-6087 4208);
FORCEPROP 2 LAST CDS_LIB mstr_standard
J 0
(-6025 4200);
DISPLAY 0.723404 (-6025 4200);
PAINT MONO (-6025 4200);
DISPLAY INVISIBLE (-6025 4200);
FORCEPROP 1 LAST BODY_TYPE PLUMBING
J 0
(-6025 4250);
DISPLAY 0.872340 (-6025 4250);
PAINT GREEN (-6025 4250);
DISPLAY INVISIBLE (-6025 4250);
FORCEPROP 1 LAST HDL_TAP TRUE
J 0
(-5700 4075);
DISPLAY 0.872340 (-5700 4075);
DISPLAY INVISIBLE (-5700 4075);
FORCEPROP 1 LAST PATH I102
J 0
(-6027 4200);
DISPLAY 0.872340 (-6027 4200);
PAINT GREEN (-6027 4200);
DISPLAY INVISIBLE (-6027 4200);
FORCEADD TAP..1
(-6025 4250);
FORCEPROP 3 LASTPIN (-6075 4250) SIG_NAME M_H_CPU0_SA_DQ<9>
J 0
(-6065 4260);
DISPLAY 0.659574 (-6065 4260);
PAINT MONO (-6065 4260);
DISPLAY INVISIBLE (-6065 4260);
FORCEPROP 1 LASTPIN (-6075 4250) BN 9
J 0
(-6087 4258);
DISPLAY 0.489362 (-6087 4258);
PAINT GREEN (-6087 4258);
FORCEPROP 2 LAST CDS_LIB mstr_standard
J 0
(-6025 4250);
DISPLAY 0.723404 (-6025 4250);
PAINT MONO (-6025 4250);
DISPLAY INVISIBLE (-6025 4250);
FORCEPROP 1 LAST BODY_TYPE PLUMBING
J 0
(-6025 4300);
DISPLAY 0.872340 (-6025 4300);
PAINT GREEN (-6025 4300);
DISPLAY INVISIBLE (-6025 4300);
FORCEPROP 1 LAST HDL_TAP TRUE
J 0
(-5700 4125);
DISPLAY 0.872340 (-5700 4125);
DISPLAY INVISIBLE (-5700 4125);
FORCEPROP 1 LAST PATH I103
J 0
(-6027 4250);
DISPLAY 0.872340 (-6027 4250);
PAINT GREEN (-6027 4250);
DISPLAY INVISIBLE (-6027 4250);
FORCEADD TAP..1
(-6025 4350);
FORCEPROP 3 LASTPIN (-6075 4350) SIG_NAME M_H_CPU0_SA_DQ<11>
J 0
(-6065 4360);
DISPLAY 0.659574 (-6065 4360);
PAINT MONO (-6065 4360);
DISPLAY INVISIBLE (-6065 4360);
FORCEPROP 1 LASTPIN (-6075 4350) BN 11
J 0
(-6087 4358);
DISPLAY 0.489362 (-6087 4358);
PAINT GREEN (-6087 4358);
FORCEPROP 2 LAST CDS_LIB mstr_standard
J 0
(-6025 4350);
DISPLAY 0.723404 (-6025 4350);
PAINT MONO (-6025 4350);
DISPLAY INVISIBLE (-6025 4350);
FORCEPROP 1 LAST BODY_TYPE PLUMBING
J 0
(-6025 4400);
DISPLAY 0.872340 (-6025 4400);
PAINT GREEN (-6025 4400);
DISPLAY INVISIBLE (-6025 4400);
FORCEPROP 1 LAST HDL_TAP TRUE
J 0
(-5700 4225);
DISPLAY 0.872340 (-5700 4225);
DISPLAY INVISIBLE (-5700 4225);
FORCEPROP 1 LAST PATH I104
J 0
(-6027 4350);
DISPLAY 0.872340 (-6027 4350);
PAINT GREEN (-6027 4350);
DISPLAY INVISIBLE (-6027 4350);
FORCEADD TAP..1
(-6025 4400);
FORCEPROP 3 LASTPIN (-6075 4400) SIG_NAME M_H_CPU0_SA_DQ<12>
J 0
(-6065 4410);
DISPLAY 0.659574 (-6065 4410);
PAINT MONO (-6065 4410);
DISPLAY INVISIBLE (-6065 4410);
FORCEPROP 1 LASTPIN (-6075 4400) BN 12
J 0
(-6087 4408);
DISPLAY 0.489362 (-6087 4408);
PAINT GREEN (-6087 4408);
FORCEPROP 2 LAST CDS_LIB mstr_standard
J 0
(-6025 4400);
DISPLAY 0.723404 (-6025 4400);
PAINT MONO (-6025 4400);
DISPLAY INVISIBLE (-6025 4400);
FORCEPROP 1 LAST BODY_TYPE PLUMBING
J 0
(-6025 4450);
DISPLAY 0.872340 (-6025 4450);
PAINT GREEN (-6025 4450);
DISPLAY INVISIBLE (-6025 4450);
FORCEPROP 1 LAST HDL_TAP TRUE
J 0
(-5700 4275);
DISPLAY 0.872340 (-5700 4275);
DISPLAY INVISIBLE (-5700 4275);
FORCEPROP 1 LAST PATH I105
J 0
(-6027 4400);
DISPLAY 0.872340 (-6027 4400);
PAINT GREEN (-6027 4400);
DISPLAY INVISIBLE (-6027 4400);
FORCEADD TAP..1
(-6025 4450);
FORCEPROP 3 LASTPIN (-6075 4450) SIG_NAME M_H_CPU0_SA_DQ<13>
J 0
(-6065 4460);
DISPLAY 0.659574 (-6065 4460);
PAINT MONO (-6065 4460);
DISPLAY INVISIBLE (-6065 4460);
FORCEPROP 1 LASTPIN (-6075 4450) BN 13
J 0
(-6087 4458);
DISPLAY 0.489362 (-6087 4458);
PAINT GREEN (-6087 4458);
FORCEPROP 2 LAST CDS_LIB mstr_standard
J 0
(-6025 4450);
DISPLAY 0.723404 (-6025 4450);
PAINT MONO (-6025 4450);
DISPLAY INVISIBLE (-6025 4450);
FORCEPROP 1 LAST BODY_TYPE PLUMBING
J 0
(-6025 4500);
DISPLAY 0.872340 (-6025 4500);
PAINT GREEN (-6025 4500);
DISPLAY INVISIBLE (-6025 4500);
FORCEPROP 1 LAST HDL_TAP TRUE
J 0
(-5700 4325);
DISPLAY 0.872340 (-5700 4325);
DISPLAY INVISIBLE (-5700 4325);
FORCEPROP 1 LAST PATH I106
J 0
(-6027 4450);
DISPLAY 0.872340 (-6027 4450);
PAINT GREEN (-6027 4450);
DISPLAY INVISIBLE (-6027 4450);
FORCEADD TAP..1
(-6025 4500);
FORCEPROP 3 LASTPIN (-6075 4500) SIG_NAME M_H_CPU0_SA_DQ<14>
J 0
(-6065 4510);
DISPLAY 0.659574 (-6065 4510);
PAINT MONO (-6065 4510);
DISPLAY INVISIBLE (-6065 4510);
FORCEPROP 1 LASTPIN (-6075 4500) BN 14
J 0
(-6087 4508);
DISPLAY 0.489362 (-6087 4508);
PAINT GREEN (-6087 4508);
FORCEPROP 2 LAST CDS_LIB mstr_standard
J 0
(-6025 4500);
DISPLAY 0.723404 (-6025 4500);
PAINT MONO (-6025 4500);
DISPLAY INVISIBLE (-6025 4500);
FORCEPROP 1 LAST BODY_TYPE PLUMBING
J 0
(-6025 4550);
DISPLAY 0.872340 (-6025 4550);
PAINT GREEN (-6025 4550);
DISPLAY INVISIBLE (-6025 4550);
FORCEPROP 1 LAST HDL_TAP TRUE
J 0
(-5700 4375);
DISPLAY 0.872340 (-5700 4375);
DISPLAY INVISIBLE (-5700 4375);
FORCEPROP 1 LAST PATH I107
J 0
(-6027 4500);
DISPLAY 0.872340 (-6027 4500);
PAINT GREEN (-6027 4500);
DISPLAY INVISIBLE (-6027 4500);
FORCEADD TAP..1
(-6025 4300);
FORCEPROP 3 LASTPIN (-6075 4300) SIG_NAME M_H_CPU0_SA_DQ<10>
J 0
(-6065 4310);
DISPLAY 0.659574 (-6065 4310);
PAINT MONO (-6065 4310);
DISPLAY INVISIBLE (-6065 4310);
FORCEPROP 1 LASTPIN (-6075 4300) BN 10
J 0
(-6087 4308);
DISPLAY 0.489362 (-6087 4308);
PAINT GREEN (-6087 4308);
FORCEPROP 2 LAST CDS_LIB mstr_standard
J 0
(-6025 4300);
DISPLAY 0.723404 (-6025 4300);
PAINT MONO (-6025 4300);
DISPLAY INVISIBLE (-6025 4300);
FORCEPROP 1 LAST BODY_TYPE PLUMBING
J 0
(-6025 4350);
DISPLAY 0.872340 (-6025 4350);
PAINT GREEN (-6025 4350);
DISPLAY INVISIBLE (-6025 4350);
FORCEPROP 1 LAST HDL_TAP TRUE
J 0
(-5700 4175);
DISPLAY 0.872340 (-5700 4175);
DISPLAY INVISIBLE (-5700 4175);
FORCEPROP 1 LAST PATH I108
J 0
(-6027 4300);
DISPLAY 0.872340 (-6027 4300);
PAINT GREEN (-6027 4300);
DISPLAY INVISIBLE (-6027 4300);
FORCEADD TAP..1
(-6025 4750);
FORCEPROP 3 LASTPIN (-6075 4750) SIG_NAME M_H_CPU0_SA_DQ<19>
J 0
(-6065 4760);
DISPLAY 0.659574 (-6065 4760);
PAINT MONO (-6065 4760);
DISPLAY INVISIBLE (-6065 4760);
FORCEPROP 1 LASTPIN (-6075 4750) BN 19
J 0
(-6087 4758);
DISPLAY 0.489362 (-6087 4758);
PAINT GREEN (-6087 4758);
FORCEPROP 2 LAST CDS_LIB mstr_standard
J 0
(-6025 4750);
DISPLAY 0.723404 (-6025 4750);
PAINT MONO (-6025 4750);
DISPLAY INVISIBLE (-6025 4750);
FORCEPROP 1 LAST BODY_TYPE PLUMBING
J 0
(-6025 4800);
DISPLAY 0.872340 (-6025 4800);
PAINT GREEN (-6025 4800);
DISPLAY INVISIBLE (-6025 4800);
FORCEPROP 1 LAST HDL_TAP TRUE
J 0
(-5700 4625);
DISPLAY 0.872340 (-5700 4625);
DISPLAY INVISIBLE (-5700 4625);
FORCEPROP 1 LAST PATH I109
J 0
(-6027 4750);
DISPLAY 0.872340 (-6027 4750);
PAINT GREEN (-6027 4750);
DISPLAY INVISIBLE (-6027 4750);
FORCEADD OFFPAGE..6
(-8325 4000);
FORCEPROP 2 LAST $XR0 17 
J 0
(-8574 4000);
DISPLAY 0.638298 (-8574 4000);
PAINT MONO (-8574 4000);
FORCEPROP 2 LAST PATH I11
J 0
(-8275 4075);
DISPLAY 1.021277 (-8275 4075);
DISPLAY INVISIBLE (-8275 4075);
FORCEPROP 1 LAST COMMENT_BODY TRUE
J 0
(-8225 3925);
DISPLAY 0.872340 (-8225 3925);
PAINT GREEN (-8225 3925);
DISPLAY INVISIBLE (-8225 3925);
FORCEPROP 1 LAST OFFPAGE TRUE
J 0
(-8000 3875);
DISPLAY 0.872340 (-8000 3875);
PAINT GREEN (-8000 3875);
DISPLAY INVISIBLE (-8000 3875);
FORCEPROP 2 LAST CDS_LIB mstr_standard
J 0
(-8325 4000);
DISPLAY 0.723404 (-8325 4000);
PAINT MONO (-8325 4000);
DISPLAY INVISIBLE (-8325 4000);
FORCEADD TAP..1
(-6025 4600);
FORCEPROP 3 LASTPIN (-6075 4600) SIG_NAME M_H_CPU0_SA_DQ<16>
J 0
(-6065 4610);
DISPLAY 0.659574 (-6065 4610);
PAINT MONO (-6065 4610);
DISPLAY INVISIBLE (-6065 4610);
FORCEPROP 1 LASTPIN (-6075 4600) BN 16
J 0
(-6087 4608);
DISPLAY 0.489362 (-6087 4608);
PAINT GREEN (-6087 4608);
FORCEPROP 2 LAST CDS_LIB mstr_standard
J 0
(-6025 4600);
DISPLAY 0.723404 (-6025 4600);
PAINT MONO (-6025 4600);
DISPLAY INVISIBLE (-6025 4600);
FORCEPROP 1 LAST BODY_TYPE PLUMBING
J 0
(-6025 4650);
DISPLAY 0.872340 (-6025 4650);
PAINT GREEN (-6025 4650);
DISPLAY INVISIBLE (-6025 4650);
FORCEPROP 1 LAST HDL_TAP TRUE
J 0
(-5700 4475);
DISPLAY 0.872340 (-5700 4475);
DISPLAY INVISIBLE (-5700 4475);
FORCEPROP 1 LAST PATH I110
J 0
(-6027 4600);
DISPLAY 0.872340 (-6027 4600);
PAINT GREEN (-6027 4600);
DISPLAY INVISIBLE (-6027 4600);
FORCEADD TAP..1
(-6025 4700);
FORCEPROP 3 LASTPIN (-6075 4700) SIG_NAME M_H_CPU0_SA_DQ<18>
J 0
(-6065 4710);
DISPLAY 0.659574 (-6065 4710);
PAINT MONO (-6065 4710);
DISPLAY INVISIBLE (-6065 4710);
FORCEPROP 1 LASTPIN (-6075 4700) BN 18
J 0
(-6087 4708);
DISPLAY 0.489362 (-6087 4708);
PAINT GREEN (-6087 4708);
FORCEPROP 2 LAST CDS_LIB mstr_standard
J 0
(-6025 4700);
DISPLAY 0.723404 (-6025 4700);
PAINT MONO (-6025 4700);
DISPLAY INVISIBLE (-6025 4700);
FORCEPROP 1 LAST BODY_TYPE PLUMBING
J 0
(-6025 4750);
DISPLAY 0.872340 (-6025 4750);
PAINT GREEN (-6025 4750);
DISPLAY INVISIBLE (-6025 4750);
FORCEPROP 1 LAST HDL_TAP TRUE
J 0
(-5700 4575);
DISPLAY 0.872340 (-5700 4575);
DISPLAY INVISIBLE (-5700 4575);
FORCEPROP 1 LAST PATH I111
J 0
(-6027 4700);
DISPLAY 0.872340 (-6027 4700);
PAINT GREEN (-6027 4700);
DISPLAY INVISIBLE (-6027 4700);
FORCEADD TAP..1
(-6025 4650);
FORCEPROP 3 LASTPIN (-6075 4650) SIG_NAME M_H_CPU0_SA_DQ<17>
J 0
(-6065 4660);
DISPLAY 0.659574 (-6065 4660);
PAINT MONO (-6065 4660);
DISPLAY INVISIBLE (-6065 4660);
FORCEPROP 1 LASTPIN (-6075 4650) BN 17
J 0
(-6087 4658);
DISPLAY 0.489362 (-6087 4658);
PAINT GREEN (-6087 4658);
FORCEPROP 2 LAST CDS_LIB mstr_standard
J 0
(-6025 4650);
DISPLAY 0.723404 (-6025 4650);
PAINT MONO (-6025 4650);
DISPLAY INVISIBLE (-6025 4650);
FORCEPROP 1 LAST BODY_TYPE PLUMBING
J 0
(-6025 4700);
DISPLAY 0.872340 (-6025 4700);
PAINT GREEN (-6025 4700);
DISPLAY INVISIBLE (-6025 4700);
FORCEPROP 1 LAST HDL_TAP TRUE
J 0
(-5700 4525);
DISPLAY 0.872340 (-5700 4525);
DISPLAY INVISIBLE (-5700 4525);
FORCEPROP 1 LAST PATH I112
J 0
(-6027 4650);
DISPLAY 0.872340 (-6027 4650);
PAINT GREEN (-6027 4650);
DISPLAY INVISIBLE (-6027 4650);
FORCEADD TAP..1
(-6025 4550);
FORCEPROP 3 LASTPIN (-6075 4550) SIG_NAME M_H_CPU0_SA_DQ<15>
J 0
(-6065 4560);
DISPLAY 0.659574 (-6065 4560);
PAINT MONO (-6065 4560);
DISPLAY INVISIBLE (-6065 4560);
FORCEPROP 1 LASTPIN (-6075 4550) BN 15
J 0
(-6087 4558);
DISPLAY 0.489362 (-6087 4558);
PAINT GREEN (-6087 4558);
FORCEPROP 2 LAST CDS_LIB mstr_standard
J 0
(-6025 4550);
DISPLAY 0.723404 (-6025 4550);
PAINT MONO (-6025 4550);
DISPLAY INVISIBLE (-6025 4550);
FORCEPROP 1 LAST BODY_TYPE PLUMBING
J 0
(-6025 4600);
DISPLAY 0.872340 (-6025 4600);
PAINT GREEN (-6025 4600);
DISPLAY INVISIBLE (-6025 4600);
FORCEPROP 1 LAST HDL_TAP TRUE
J 0
(-5700 4425);
DISPLAY 0.872340 (-5700 4425);
DISPLAY INVISIBLE (-5700 4425);
FORCEPROP 1 LAST PATH I113
J 0
(-6027 4550);
DISPLAY 0.872340 (-6027 4550);
PAINT GREEN (-6027 4550);
DISPLAY INVISIBLE (-6027 4550);
FORCEADD TAP..1
(-6025 4800);
FORCEPROP 3 LASTPIN (-6075 4800) SIG_NAME M_H_CPU0_SA_DQ<20>
J 0
(-6065 4810);
DISPLAY 0.659574 (-6065 4810);
PAINT MONO (-6065 4810);
DISPLAY INVISIBLE (-6065 4810);
FORCEPROP 1 LASTPIN (-6075 4800) BN 20
J 0
(-6087 4808);
DISPLAY 0.489362 (-6087 4808);
PAINT GREEN (-6087 4808);
FORCEPROP 2 LAST CDS_LIB mstr_standard
J 0
(-6025 4800);
DISPLAY 0.723404 (-6025 4800);
PAINT MONO (-6025 4800);
DISPLAY INVISIBLE (-6025 4800);
FORCEPROP 1 LAST BODY_TYPE PLUMBING
J 0
(-6025 4850);
DISPLAY 0.872340 (-6025 4850);
PAINT GREEN (-6025 4850);
DISPLAY INVISIBLE (-6025 4850);
FORCEPROP 1 LAST HDL_TAP TRUE
J 0
(-5700 4675);
DISPLAY 0.872340 (-5700 4675);
DISPLAY INVISIBLE (-5700 4675);
FORCEPROP 1 LAST PATH I114
J 0
(-6027 4800);
DISPLAY 0.872340 (-6027 4800);
PAINT GREEN (-6027 4800);
DISPLAY INVISIBLE (-6027 4800);
FORCEADD TAP..1
(-6025 4850);
FORCEPROP 3 LASTPIN (-6075 4850) SIG_NAME M_H_CPU0_SA_DQ<21>
J 0
(-6065 4860);
DISPLAY 0.659574 (-6065 4860);
PAINT MONO (-6065 4860);
DISPLAY INVISIBLE (-6065 4860);
FORCEPROP 1 LASTPIN (-6075 4850) BN 21
J 0
(-6087 4858);
DISPLAY 0.489362 (-6087 4858);
PAINT GREEN (-6087 4858);
FORCEPROP 2 LAST CDS_LIB mstr_standard
J 0
(-6025 4850);
DISPLAY 0.723404 (-6025 4850);
PAINT MONO (-6025 4850);
DISPLAY INVISIBLE (-6025 4850);
FORCEPROP 1 LAST BODY_TYPE PLUMBING
J 0
(-6025 4900);
DISPLAY 0.872340 (-6025 4900);
PAINT GREEN (-6025 4900);
DISPLAY INVISIBLE (-6025 4900);
FORCEPROP 1 LAST HDL_TAP TRUE
J 0
(-5700 4725);
DISPLAY 0.872340 (-5700 4725);
DISPLAY INVISIBLE (-5700 4725);
FORCEPROP 1 LAST PATH I115
J 0
(-6027 4850);
DISPLAY 0.872340 (-6027 4850);
PAINT GREEN (-6027 4850);
DISPLAY INVISIBLE (-6027 4850);
FORCEADD TAP..1
(-6025 4900);
FORCEPROP 3 LASTPIN (-6075 4900) SIG_NAME M_H_CPU0_SA_DQ<22>
J 0
(-6065 4910);
DISPLAY 0.659574 (-6065 4910);
PAINT MONO (-6065 4910);
DISPLAY INVISIBLE (-6065 4910);
FORCEPROP 1 LASTPIN (-6075 4900) BN 22
J 0
(-6087 4908);
DISPLAY 0.489362 (-6087 4908);
PAINT GREEN (-6087 4908);
FORCEPROP 2 LAST CDS_LIB mstr_standard
J 0
(-6025 4900);
DISPLAY 0.723404 (-6025 4900);
PAINT MONO (-6025 4900);
DISPLAY INVISIBLE (-6025 4900);
FORCEPROP 1 LAST BODY_TYPE PLUMBING
J 0
(-6025 4950);
DISPLAY 0.872340 (-6025 4950);
PAINT GREEN (-6025 4950);
DISPLAY INVISIBLE (-6025 4950);
FORCEPROP 1 LAST HDL_TAP TRUE
J 0
(-5700 4775);
DISPLAY 0.872340 (-5700 4775);
DISPLAY INVISIBLE (-5700 4775);
FORCEPROP 1 LAST PATH I116
J 0
(-6027 4900);
DISPLAY 0.872340 (-6027 4900);
PAINT GREEN (-6027 4900);
DISPLAY INVISIBLE (-6027 4900);
FORCEADD TAP..1
(-6025 5050);
FORCEPROP 3 LASTPIN (-6075 5050) SIG_NAME M_H_CPU0_SA_DQ<25>
J 0
(-6065 5060);
DISPLAY 0.659574 (-6065 5060);
PAINT MONO (-6065 5060);
DISPLAY INVISIBLE (-6065 5060);
FORCEPROP 1 LASTPIN (-6075 5050) BN 25
J 0
(-6087 5058);
DISPLAY 0.489362 (-6087 5058);
PAINT GREEN (-6087 5058);
FORCEPROP 2 LAST CDS_LIB mstr_standard
J 0
(-6025 5050);
DISPLAY 0.723404 (-6025 5050);
PAINT MONO (-6025 5050);
DISPLAY INVISIBLE (-6025 5050);
FORCEPROP 1 LAST BODY_TYPE PLUMBING
J 0
(-6025 5100);
DISPLAY 0.872340 (-6025 5100);
PAINT GREEN (-6025 5100);
DISPLAY INVISIBLE (-6025 5100);
FORCEPROP 1 LAST HDL_TAP TRUE
J 0
(-5700 4925);
DISPLAY 0.872340 (-5700 4925);
DISPLAY INVISIBLE (-5700 4925);
FORCEPROP 1 LAST PATH I117
J 0
(-6027 5050);
DISPLAY 0.872340 (-6027 5050);
PAINT GREEN (-6027 5050);
DISPLAY INVISIBLE (-6027 5050);
FORCEADD TAP..1
(-6025 4950);
FORCEPROP 3 LASTPIN (-6075 4950) SIG_NAME M_H_CPU0_SA_DQ<23>
J 0
(-6065 4960);
DISPLAY 0.659574 (-6065 4960);
PAINT MONO (-6065 4960);
DISPLAY INVISIBLE (-6065 4960);
FORCEPROP 1 LASTPIN (-6075 4950) BN 23
J 0
(-6087 4958);
DISPLAY 0.489362 (-6087 4958);
PAINT GREEN (-6087 4958);
FORCEPROP 2 LAST CDS_LIB mstr_standard
J 0
(-6025 4950);
DISPLAY 0.723404 (-6025 4950);
PAINT MONO (-6025 4950);
DISPLAY INVISIBLE (-6025 4950);
FORCEPROP 1 LAST BODY_TYPE PLUMBING
J 0
(-6025 5000);
DISPLAY 0.872340 (-6025 5000);
PAINT GREEN (-6025 5000);
DISPLAY INVISIBLE (-6025 5000);
FORCEPROP 1 LAST HDL_TAP TRUE
J 0
(-5700 4825);
DISPLAY 0.872340 (-5700 4825);
DISPLAY INVISIBLE (-5700 4825);
FORCEPROP 1 LAST PATH I118
J 0
(-6027 4950);
DISPLAY 0.872340 (-6027 4950);
PAINT GREEN (-6027 4950);
DISPLAY INVISIBLE (-6027 4950);
FORCEADD TAP..1
(-6025 5000);
FORCEPROP 3 LASTPIN (-6075 5000) SIG_NAME M_H_CPU0_SA_DQ<24>
J 0
(-6065 5010);
DISPLAY 0.659574 (-6065 5010);
PAINT MONO (-6065 5010);
DISPLAY INVISIBLE (-6065 5010);
FORCEPROP 1 LASTPIN (-6075 5000) BN 24
J 0
(-6087 5008);
DISPLAY 0.489362 (-6087 5008);
PAINT GREEN (-6087 5008);
FORCEPROP 2 LAST CDS_LIB mstr_standard
J 0
(-6025 5000);
DISPLAY 0.723404 (-6025 5000);
PAINT MONO (-6025 5000);
DISPLAY INVISIBLE (-6025 5000);
FORCEPROP 1 LAST BODY_TYPE PLUMBING
J 0
(-6025 5050);
DISPLAY 0.872340 (-6025 5050);
PAINT GREEN (-6025 5050);
DISPLAY INVISIBLE (-6025 5050);
FORCEPROP 1 LAST HDL_TAP TRUE
J 0
(-5700 4875);
DISPLAY 0.872340 (-5700 4875);
DISPLAY INVISIBLE (-5700 4875);
FORCEPROP 1 LAST PATH I119
J 0
(-6027 5000);
DISPLAY 0.872340 (-6027 5000);
PAINT GREEN (-6027 5000);
DISPLAY INVISIBLE (-6027 5000);
FORCEADD OFFPAGE..1
(-8325 4050);
FORCEPROP 2 LAST $XR0 17 
J 0
(-8546 4050);
DISPLAY 0.638298 (-8546 4050);
PAINT MONO (-8546 4050);
FORCEPROP 2 LAST PATH I12
J 0
(-8275 4125);
DISPLAY 1.021277 (-8275 4125);
DISPLAY INVISIBLE (-8275 4125);
FORCEPROP 1 LAST COMMENT_BODY TRUE
J 0
(-8200 3950);
DISPLAY 0.872340 (-8200 3950);
PAINT GREEN (-8200 3950);
DISPLAY INVISIBLE (-8200 3950);
FORCEPROP 1 LAST OFFPAGE TRUE
J 0
(-8000 3925);
DISPLAY 0.872340 (-8000 3925);
PAINT GREEN (-8000 3925);
DISPLAY INVISIBLE (-8000 3925);
FORCEPROP 2 LAST CDS_LIB mstr_standard
J 0
(-8325 4050);
DISPLAY 0.808511 (-8325 4050);
DISPLAY INVISIBLE (-8325 4050);
FORCEADD TAP..1
(-6025 5250);
FORCEPROP 3 LASTPIN (-6075 5250) SIG_NAME M_H_CPU0_SA_DQ<29>
J 0
(-6065 5260);
DISPLAY 0.659574 (-6065 5260);
PAINT MONO (-6065 5260);
DISPLAY INVISIBLE (-6065 5260);
FORCEPROP 1 LASTPIN (-6075 5250) BN 29
J 0
(-6087 5258);
DISPLAY 0.489362 (-6087 5258);
PAINT GREEN (-6087 5258);
FORCEPROP 2 LAST CDS_LIB mstr_standard
J 0
(-6025 5250);
DISPLAY 0.723404 (-6025 5250);
PAINT MONO (-6025 5250);
DISPLAY INVISIBLE (-6025 5250);
FORCEPROP 1 LAST BODY_TYPE PLUMBING
J 0
(-6025 5300);
DISPLAY 0.872340 (-6025 5300);
PAINT GREEN (-6025 5300);
DISPLAY INVISIBLE (-6025 5300);
FORCEPROP 1 LAST HDL_TAP TRUE
J 0
(-5700 5125);
DISPLAY 0.872340 (-5700 5125);
DISPLAY INVISIBLE (-5700 5125);
FORCEPROP 1 LAST PATH I120
J 0
(-6027 5250);
DISPLAY 0.872340 (-6027 5250);
PAINT GREEN (-6027 5250);
DISPLAY INVISIBLE (-6027 5250);
FORCEADD TAP..1
(-6025 5300);
FORCEPROP 3 LASTPIN (-6075 5300) SIG_NAME M_H_CPU0_SA_DQ<30>
J 0
(-6065 5310);
DISPLAY 0.659574 (-6065 5310);
PAINT MONO (-6065 5310);
DISPLAY INVISIBLE (-6065 5310);
FORCEPROP 1 LASTPIN (-6075 5300) BN 30
J 0
(-6087 5308);
DISPLAY 0.489362 (-6087 5308);
PAINT GREEN (-6087 5308);
FORCEPROP 2 LAST CDS_LIB mstr_standard
J 0
(-6025 5300);
DISPLAY 0.723404 (-6025 5300);
PAINT MONO (-6025 5300);
DISPLAY INVISIBLE (-6025 5300);
FORCEPROP 1 LAST BODY_TYPE PLUMBING
J 0
(-6025 5350);
DISPLAY 0.872340 (-6025 5350);
PAINT GREEN (-6025 5350);
DISPLAY INVISIBLE (-6025 5350);
FORCEPROP 1 LAST HDL_TAP TRUE
J 0
(-5700 5175);
DISPLAY 0.872340 (-5700 5175);
DISPLAY INVISIBLE (-5700 5175);
FORCEPROP 1 LAST PATH I121
J 0
(-6027 5300);
DISPLAY 0.872340 (-6027 5300);
PAINT GREEN (-6027 5300);
DISPLAY INVISIBLE (-6027 5300);
FORCEADD TAP..1
(-6025 5200);
FORCEPROP 3 LASTPIN (-6075 5200) SIG_NAME M_H_CPU0_SA_DQ<28>
J 0
(-6065 5210);
DISPLAY 0.659574 (-6065 5210);
PAINT MONO (-6065 5210);
DISPLAY INVISIBLE (-6065 5210);
FORCEPROP 1 LASTPIN (-6075 5200) BN 28
J 0
(-6087 5208);
DISPLAY 0.489362 (-6087 5208);
PAINT GREEN (-6087 5208);
FORCEPROP 2 LAST CDS_LIB mstr_standard
J 0
(-6025 5200);
DISPLAY 0.723404 (-6025 5200);
PAINT MONO (-6025 5200);
DISPLAY INVISIBLE (-6025 5200);
FORCEPROP 1 LAST BODY_TYPE PLUMBING
J 0
(-6025 5250);
DISPLAY 0.872340 (-6025 5250);
PAINT GREEN (-6025 5250);
DISPLAY INVISIBLE (-6025 5250);
FORCEPROP 1 LAST HDL_TAP TRUE
J 0
(-5700 5075);
DISPLAY 0.872340 (-5700 5075);
DISPLAY INVISIBLE (-5700 5075);
FORCEPROP 1 LAST PATH I122
J 0
(-6027 5200);
DISPLAY 0.872340 (-6027 5200);
PAINT GREEN (-6027 5200);
DISPLAY INVISIBLE (-6027 5200);
FORCEADD TAP..1
(-6025 5150);
FORCEPROP 3 LASTPIN (-6075 5150) SIG_NAME M_H_CPU0_SA_DQ<27>
J 0
(-6065 5160);
DISPLAY 0.659574 (-6065 5160);
PAINT MONO (-6065 5160);
DISPLAY INVISIBLE (-6065 5160);
FORCEPROP 1 LASTPIN (-6075 5150) BN 27
J 0
(-6087 5158);
DISPLAY 0.489362 (-6087 5158);
PAINT GREEN (-6087 5158);
FORCEPROP 2 LAST CDS_LIB mstr_standard
J 0
(-6025 5150);
DISPLAY 0.723404 (-6025 5150);
PAINT MONO (-6025 5150);
DISPLAY INVISIBLE (-6025 5150);
FORCEPROP 1 LAST BODY_TYPE PLUMBING
J 0
(-6025 5200);
DISPLAY 0.872340 (-6025 5200);
PAINT GREEN (-6025 5200);
DISPLAY INVISIBLE (-6025 5200);
FORCEPROP 1 LAST HDL_TAP TRUE
J 0
(-5700 5025);
DISPLAY 0.872340 (-5700 5025);
DISPLAY INVISIBLE (-5700 5025);
FORCEPROP 1 LAST PATH I123
J 0
(-6027 5150);
DISPLAY 0.872340 (-6027 5150);
PAINT GREEN (-6027 5150);
DISPLAY INVISIBLE (-6027 5150);
FORCEADD TAP..1
(-6025 5100);
FORCEPROP 3 LASTPIN (-6075 5100) SIG_NAME M_H_CPU0_SA_DQ<26>
J 0
(-6065 5110);
DISPLAY 0.659574 (-6065 5110);
PAINT MONO (-6065 5110);
DISPLAY INVISIBLE (-6065 5110);
FORCEPROP 1 LASTPIN (-6075 5100) BN 26
J 0
(-6087 5108);
DISPLAY 0.489362 (-6087 5108);
PAINT GREEN (-6087 5108);
FORCEPROP 2 LAST CDS_LIB mstr_standard
J 0
(-6025 5100);
DISPLAY 0.723404 (-6025 5100);
PAINT MONO (-6025 5100);
DISPLAY INVISIBLE (-6025 5100);
FORCEPROP 1 LAST BODY_TYPE PLUMBING
J 0
(-6025 5150);
DISPLAY 0.872340 (-6025 5150);
PAINT GREEN (-6025 5150);
DISPLAY INVISIBLE (-6025 5150);
FORCEPROP 1 LAST HDL_TAP TRUE
J 0
(-5700 4975);
DISPLAY 0.872340 (-5700 4975);
DISPLAY INVISIBLE (-5700 4975);
FORCEPROP 1 LAST PATH I124
J 0
(-6027 5100);
DISPLAY 0.872340 (-6027 5100);
PAINT GREEN (-6027 5100);
DISPLAY INVISIBLE (-6027 5100);
FORCEADD TAP..1
(-6025 5350);
FORCEPROP 3 LASTPIN (-6075 5350) SIG_NAME M_H_CPU0_SA_DQ<31>
J 0
(-6065 5360);
DISPLAY 0.659574 (-6065 5360);
PAINT MONO (-6065 5360);
DISPLAY INVISIBLE (-6065 5360);
FORCEPROP 1 LASTPIN (-6075 5350) BN 31
J 0
(-6087 5358);
DISPLAY 0.489362 (-6087 5358);
PAINT GREEN (-6087 5358);
FORCEPROP 2 LAST CDS_LIB mstr_standard
J 0
(-6025 5350);
DISPLAY 0.723404 (-6025 5350);
PAINT MONO (-6025 5350);
DISPLAY INVISIBLE (-6025 5350);
FORCEPROP 1 LAST BODY_TYPE PLUMBING
J 0
(-6025 5400);
DISPLAY 0.872340 (-6025 5400);
PAINT GREEN (-6025 5400);
DISPLAY INVISIBLE (-6025 5400);
FORCEPROP 1 LAST HDL_TAP TRUE
J 0
(-5700 5225);
DISPLAY 0.872340 (-5700 5225);
DISPLAY INVISIBLE (-5700 5225);
FORCEPROP 1 LAST PATH I125
J 0
(-6027 5350);
DISPLAY 0.872340 (-6027 5350);
PAINT GREEN (-6027 5350);
DISPLAY INVISIBLE (-6027 5350);
FORCEADD OFFPAGE..3
(-5350 5400);
FORCEPROP 2 LAST $XR0 17 
J 0
(-5136 5400);
DISPLAY 0.638298 (-5136 5400);
PAINT MONO (-5136 5400);
FORCEPROP 2 LAST PATH I126
J 0
(-5150 5475);
DISPLAY 1.021277 (-5150 5475);
DISPLAY INVISIBLE (-5150 5475);
FORCEPROP 1 LAST COMMENT_BODY TRUE
J 0
(-5400 5300);
DISPLAY 0.872340 (-5400 5300);
PAINT GREEN (-5400 5300);
DISPLAY INVISIBLE (-5400 5300);
FORCEPROP 1 LAST OFFPAGE TRUE
J 0
(-5025 5275);
DISPLAY 0.872340 (-5025 5275);
PAINT GREEN (-5025 5275);
DISPLAY INVISIBLE (-5025 5275);
FORCEPROP 2 LAST CDS_LIB mstr_standard
J 0
(-5350 5400);
DISPLAY 0.723404 (-5350 5400);
PAINT MONO (-5350 5400);
DISPLAY INVISIBLE (-5350 5400);
FORCEADD OFFPAGE..5
(-7200 1350);
FORCEPROP 2 LAST $XR0 92 
J 0
(-7424 1350);
DISPLAY 0.638298 (-7424 1350);
PAINT MONO (-7424 1350);
FORCEPROP 2 LAST PATH I127
J 0
(-7450 1400);
DISPLAY 1.021277 (-7450 1400);
DISPLAY INVISIBLE (-7450 1400);
FORCEPROP 1 LAST COMMENT_BODY TRUE
J 0
(-7100 1275);
DISPLAY 0.872340 (-7100 1275);
PAINT GREEN (-7100 1275);
DISPLAY INVISIBLE (-7100 1275);
FORCEPROP 1 LAST OFFPAGE TRUE
J 0
(-6875 1225);
DISPLAY 0.872340 (-6875 1225);
PAINT GREEN (-6875 1225);
DISPLAY INVISIBLE (-6875 1225);
FORCEPROP 2 LAST CDS_LIB mstr_standard
J 0
(-7200 1350);
DISPLAY 0.808511 (-7200 1350);
DISPLAY INVISIBLE (-7200 1350);
FORCEPROP 2 LAST BOM_COST MEM
J 0
(-7275 1425);
DISPLAY 0.808511 (-7275 1425);
DISPLAY INVISIBLE (-7275 1425);
FORCEADD GND..1
(-6425 875);
FORCEPROP 3 LASTPIN (-6425 925) SIG_NAME GND\g
J 0
(-6415 935);
DISPLAY 0.659574 (-6415 935);
PAINT MONO (-6415 935);
DISPLAY INVISIBLE (-6415 935);
FORCEPROP 1 LAST SIZE 1B
J 0
(-6350 825);
DISPLAY 0.851064 (-6350 825);
PAINT GREEN (-6350 825);
DISPLAY INVISIBLE (-6350 825);
FORCEPROP 2 LAST CDS_LIB mstr_symbols
J 0
(-6425 875);
DISPLAY 0.808511 (-6425 875);
DISPLAY INVISIBLE (-6425 875);
FORCEPROP 2 LAST BOM_COST MEM
J 0
(-6525 950);
DISPLAY 0.808511 (-6525 950);
DISPLAY INVISIBLE (-6525 950);
FORCEPROP 1 LAST BODY_TYPE PLUMBING
J 0
(-6470 832);
DISPLAY 0.340426 (-6470 832);
PAINT GREEN (-6470 832);
DISPLAY INVISIBLE (-6470 832);
FORCEPROP 1 LAST PATH I128
J 0
(-6350 875);
DISPLAY 0.872340 (-6350 875);
PAINT AQUA (-6350 875);
DISPLAY INVISIBLE (-6350 875);
FORCEPROP 1 LAST VOLTAGE 0.0
J 0
(-6470 832);
DISPLAY 0.723404 (-6470 832);
PAINT SKYBLUE (-6470 832);
DISPLAY INVISIBLE (-6470 832);
FORCEPROP 1 LAST HDL_POWER GND
J 0
(-6425 1025);
DISPLAY 0.851064 (-6425 1025);
PAINT GREEN (-6425 1025);
DISPLAY INVISIBLE (-6425 1025);
FORCEADD Q_RES..2
(-6425 1175);
FORCEPROP 1 LAST LOCATION R765
J 0
(-6380 1300);
DISPLAY 0.489362 (-6380 1300);
PAINT SKYBLUE (-6380 1300);
FORCEPROP 0 LAST $SEC 1
J 0
(-6375 1350);
DISPLAY 0.680851 (-6375 1350);
PAINT MONO (-6375 1350);
DISPLAY INVISIBLE (-6375 1350);
FORCEPROP 0 LAST CDS_SEC 1
J 0
(-6375 1350);
DISPLAY 1.021277 (-6375 1350);
DISPLAY INVISIBLE (-6375 1350);
FORCEPROP 1 LASTPIN (-6425 1275) $PN 1
J 0
(-6420 1237);
DISPLAY 0.489362 (-6420 1237);
PAINT MONO (-6420 1237);
FORCEPROP 1 LASTPIN (-6425 1075) $PN 2
J 0
(-6420 1085);
DISPLAY 0.489362 (-6420 1085);
PAINT MONO (-6420 1085);
FORCEPROP 1 LAST WATTAGE 1/16W
J 0
(-6385 1150);
DISPLAY 0.489362 (-6385 1150);
PAINT SKYBLUE (-6385 1150);
FORCEPROP 1 LAST MATERIAL CHIP
J 0
(-6385 1100);
DISPLAY 0.489362 (-6385 1100);
PAINT SKYBLUE (-6385 1100);
FORCEPROP 1 LAST TOLERANCE 1%
J 0
(-6380 1200);
DISPLAY 0.489362 (-6380 1200);
PAINT SKYBLUE (-6380 1200);
FORCEPROP 1 LAST VALUE 15.4K
J 0
(-6380 1250);
DISPLAY 0.489362 (-6380 1250);
PAINT SKYBLUE (-6380 1250);
FORCEPROP 1 LAST PART_NUMBER CS31542FB02
J 0
(-6385 1050);
DISPLAY 0.489362 (-6385 1050);
PAINT SKYBLUE (-6385 1050);
FORCEPROP 1 LAST PACK_TYPE 0402LF
J 0
(-6385 1000);
DISPLAY 0.489362 (-6385 1000);
PAINT SKYBLUE (-6385 1000);
FORCEPROP 2 LAST CDS_LIB pure_quanta
J 0
(-6425 1175);
DISPLAY INVISIBLE (-6425 1175);
FORCEPROP 1 LAST PATH I129
J 0
(-6375 1350);
DISPLAY 0.978723 (-6375 1350);
PAINT WHITE (-6375 1350);
DISPLAY INVISIBLE (-6375 1350);
FORCEADD OFFPAGE..1
(-8325 4250);
FORCEPROP 2 LAST $XR0 17 
J 0
(-8546 4250);
DISPLAY 0.638298 (-8546 4250);
PAINT MONO (-8546 4250);
FORCEPROP 2 LAST PATH I13
J 0
(-8275 4325);
DISPLAY 1.021277 (-8275 4325);
DISPLAY INVISIBLE (-8275 4325);
FORCEPROP 1 LAST COMMENT_BODY TRUE
J 0
(-8200 4150);
DISPLAY 0.872340 (-8200 4150);
PAINT GREEN (-8200 4150);
DISPLAY INVISIBLE (-8200 4150);
FORCEPROP 1 LAST OFFPAGE TRUE
J 0
(-8000 4125);
DISPLAY 0.872340 (-8000 4125);
PAINT GREEN (-8000 4125);
DISPLAY INVISIBLE (-8000 4125);
FORCEPROP 2 LAST CDS_LIB mstr_standard
J 0
(-8325 4250);
DISPLAY 0.723404 (-8325 4250);
PAINT MONO (-8325 4250);
DISPLAY INVISIBLE (-8325 4250);
FORCEADD OFFPAGE..1
(-8325 4100);
FORCEPROP 2 LAST $XR0 17 
J 0
(-8546 4100);
DISPLAY 0.638298 (-8546 4100);
PAINT MONO (-8546 4100);
FORCEPROP 2 LAST PATH I14
J 0
(-8275 4175);
DISPLAY 1.021277 (-8275 4175);
DISPLAY INVISIBLE (-8275 4175);
FORCEPROP 1 LAST COMMENT_BODY TRUE
J 0
(-8200 4000);
DISPLAY 0.872340 (-8200 4000);
PAINT GREEN (-8200 4000);
DISPLAY INVISIBLE (-8200 4000);
FORCEPROP 1 LAST OFFPAGE TRUE
J 0
(-8000 3975);
DISPLAY 0.872340 (-8000 3975);
PAINT GREEN (-8000 3975);
DISPLAY INVISIBLE (-8000 3975);
FORCEPROP 2 LAST CDS_LIB mstr_standard
J 0
(-8325 4100);
DISPLAY 0.723404 (-8325 4100);
PAINT MONO (-8325 4100);
DISPLAY INVISIBLE (-8325 4100);
FORCEADD GND..1
(-2200 1875);
FORCEPROP 3 LASTPIN (-2200 1925) SIG_NAME GND\g
J 0
(-2190 1935);
DISPLAY 0.659574 (-2190 1935);
PAINT MONO (-2190 1935);
DISPLAY INVISIBLE (-2190 1935);
FORCEPROP 1 LAST SIZE 1B
J 0
(-2125 1825);
DISPLAY 0.851064 (-2125 1825);
PAINT GREEN (-2125 1825);
DISPLAY INVISIBLE (-2125 1825);
FORCEPROP 2 LAST CDS_LIB mstr_symbols
J 0
(-2200 1875);
DISPLAY 0.723404 (-2200 1875);
DISPLAY INVISIBLE (-2200 1875);
FORCEPROP 1 LAST BODY_TYPE PLUMBING
J 0
(-2245 1832);
DISPLAY 0.340426 (-2245 1832);
PAINT GREEN (-2245 1832);
DISPLAY INVISIBLE (-2245 1832);
FORCEPROP 1 LAST PATH I140
J 0
(-2125 1875);
DISPLAY 0.872340 (-2125 1875);
PAINT AQUA (-2125 1875);
DISPLAY INVISIBLE (-2125 1875);
FORCEPROP 1 LAST VOLTAGE 0.0
J 0
(-2245 1832);
DISPLAY 0.723404 (-2245 1832);
PAINT SKYBLUE (-2245 1832);
DISPLAY INVISIBLE (-2245 1832);
FORCEPROP 1 LAST HDL_POWER GND
J 0
(-2200 2025);
DISPLAY 0.851064 (-2200 2025);
PAINT GREEN (-2200 2025);
DISPLAY INVISIBLE (-2200 2025);
FORCEADD GND..1
(-400 1650);
FORCEPROP 3 LASTPIN (-400 1700) SIG_NAME GND\g
J 0
(-390 1710);
DISPLAY 0.659574 (-390 1710);
PAINT MONO (-390 1710);
DISPLAY INVISIBLE (-390 1710);
FORCEPROP 1 LAST SIZE 1B
J 0
(-325 1600);
DISPLAY 0.851064 (-325 1600);
PAINT GREEN (-325 1600);
DISPLAY INVISIBLE (-325 1600);
FORCEPROP 2 LAST CDS_LIB mstr_symbols
J 0
(-400 1650);
DISPLAY 0.723404 (-400 1650);
DISPLAY INVISIBLE (-400 1650);
FORCEPROP 1 LAST BODY_TYPE PLUMBING
J 0
(-445 1607);
DISPLAY 0.340426 (-445 1607);
PAINT GREEN (-445 1607);
DISPLAY INVISIBLE (-445 1607);
FORCEPROP 1 LAST PATH I141
J 0
(-325 1650);
DISPLAY 0.872340 (-325 1650);
PAINT AQUA (-325 1650);
DISPLAY INVISIBLE (-325 1650);
FORCEPROP 1 LAST VOLTAGE 0.0
J 0
(-445 1607);
DISPLAY 0.723404 (-445 1607);
PAINT SKYBLUE (-445 1607);
DISPLAY INVISIBLE (-445 1607);
FORCEPROP 1 LAST HDL_POWER GND
J 0
(-400 1800);
DISPLAY 0.851064 (-400 1800);
PAINT GREEN (-400 1800);
DISPLAY INVISIBLE (-400 1800);
FORCEADD OFFPAGE..1
(-8325 4200);
FORCEPROP 2 LAST $XR0 17 
J 0
(-8546 4200);
DISPLAY 0.638298 (-8546 4200);
PAINT MONO (-8546 4200);
FORCEPROP 2 LAST PATH I15
J 0
(-8275 4275);
DISPLAY 1.021277 (-8275 4275);
DISPLAY INVISIBLE (-8275 4275);
FORCEPROP 1 LAST COMMENT_BODY TRUE
J 0
(-8200 4100);
DISPLAY 0.872340 (-8200 4100);
PAINT GREEN (-8200 4100);
DISPLAY INVISIBLE (-8200 4100);
FORCEPROP 1 LAST OFFPAGE TRUE
J 0
(-8000 4075);
DISPLAY 0.872340 (-8000 4075);
PAINT GREEN (-8000 4075);
DISPLAY INVISIBLE (-8000 4075);
FORCEPROP 2 LAST CDS_LIB mstr_standard
J 0
(-8325 4200);
DISPLAY 0.808511 (-8325 4200);
DISPLAY INVISIBLE (-8325 4200);
FORCEADD OFFPAGE..1
(-8325 4500);
FORCEPROP 2 LAST $XR0 17 
J 0
(-8546 4500);
DISPLAY 0.638298 (-8546 4500);
PAINT MONO (-8546 4500);
FORCEPROP 2 LAST PATH I16
J 0
(-8275 4575);
DISPLAY 1.021277 (-8275 4575);
DISPLAY INVISIBLE (-8275 4575);
FORCEPROP 1 LAST COMMENT_BODY TRUE
J 0
(-8200 4400);
DISPLAY 0.872340 (-8200 4400);
PAINT GREEN (-8200 4400);
DISPLAY INVISIBLE (-8200 4400);
FORCEPROP 1 LAST OFFPAGE TRUE
J 0
(-8000 4375);
DISPLAY 0.872340 (-8000 4375);
PAINT GREEN (-8000 4375);
DISPLAY INVISIBLE (-8000 4375);
FORCEPROP 2 LAST CDS_LIB mstr_standard
J 0
(-8325 4500);
DISPLAY 0.808511 (-8325 4500);
DISPLAY INVISIBLE (-8325 4500);
FORCEADD OFFPAGE..1
(-8325 4400);
FORCEPROP 2 LAST $XR0 17 
J 0
(-8546 4400);
DISPLAY 0.638298 (-8546 4400);
PAINT MONO (-8546 4400);
FORCEPROP 2 LAST PATH I17
J 0
(-8275 4475);
DISPLAY 1.021277 (-8275 4475);
DISPLAY INVISIBLE (-8275 4475);
FORCEPROP 1 LAST COMMENT_BODY TRUE
J 0
(-8200 4300);
DISPLAY 0.872340 (-8200 4300);
PAINT GREEN (-8200 4300);
DISPLAY INVISIBLE (-8200 4300);
FORCEPROP 1 LAST OFFPAGE TRUE
J 0
(-8000 4275);
DISPLAY 0.872340 (-8000 4275);
PAINT GREEN (-8000 4275);
DISPLAY INVISIBLE (-8000 4275);
FORCEPROP 2 LAST CDS_LIB mstr_standard
J 0
(-8325 4400);
DISPLAY 0.723404 (-8325 4400);
PAINT MONO (-8325 4400);
DISPLAY INVISIBLE (-8325 4400);
FORCEADD SCONN288_DDR506112002KQ..3
(-1300 3650);
FORCEPROP 1 LAST LOCATION J69
J 0
(-1750 5625);
DISPLAY 0.468085 (-1750 5625);
PAINT SKYBLUE (-1750 5625);
FORCEPROP 0 LAST $SEC 3
J 0
(-1750 5775);
DISPLAY 0.680851 (-1750 5775);
PAINT MONO (-1750 5775);
DISPLAY INVISIBLE (-1750 5775);
FORCEPROP 2 LAST CDS_SEC 3
J 0
(-1750 5775);
DISPLAY 1.021277 (-1750 5775);
DISPLAY INVISIBLE (-1750 5775);
FORCEPROP 0 LASTPIN (-700 2050) $PN G1
J 0
(-690 2060);
DISPLAY 0.680851 (-690 2060);
PAINT MONO (-690 2060);
FORCEPROP 0 LASTPIN (-700 2000) $PN G2
J 0
(-690 2010);
DISPLAY 0.680851 (-690 2010);
PAINT MONO (-690 2010);
FORCEPROP 0 LASTPIN (-700 1950) $PN G3
J 0
(-690 1960);
DISPLAY 0.680851 (-690 1960);
PAINT MONO (-690 1960);
FORCEPROP 0 LASTPIN (-1900 5200) $PN 1
J 2
(-1910 5210);
DISPLAY 0.680851 (-1910 5210);
PAINT MONO (-1910 5210);
FORCEPROP 0 LASTPIN (-1900 5250) $PN 145
J 2
(-1910 5260);
DISPLAY 0.680851 (-1910 5260);
PAINT MONO (-1910 5260);
FORCEPROP 0 LASTPIN (-1900 5300) $PN 146
J 2
(-1910 5310);
DISPLAY 0.680851 (-1910 5310);
PAINT MONO (-1910 5310);
FORCEPROP 0 LASTPIN (-700 2150) $PN 6
J 0
(-690 2160);
DISPLAY 0.680851 (-690 2160);
PAINT MONO (-690 2160);
FORCEPROP 0 LASTPIN (-700 2200) $PN 8
J 0
(-690 2210);
DISPLAY 0.680851 (-690 2210);
PAINT MONO (-690 2210);
FORCEPROP 0 LASTPIN (-700 2250) $PN 10
J 0
(-690 2260);
DISPLAY 0.680851 (-690 2260);
PAINT MONO (-690 2260);
FORCEPROP 0 LASTPIN (-700 2300) $PN 13
J 0
(-690 2310);
DISPLAY 0.680851 (-690 2310);
PAINT MONO (-690 2310);
FORCEPROP 0 LASTPIN (-700 2350) $PN 15
J 0
(-690 2360);
DISPLAY 0.680851 (-690 2360);
PAINT MONO (-690 2360);
FORCEPROP 0 LASTPIN (-700 2400) $PN 17
J 0
(-690 2410);
DISPLAY 0.680851 (-690 2410);
PAINT MONO (-690 2410);
FORCEPROP 0 LASTPIN (-700 2450) $PN 19
J 0
(-690 2460);
DISPLAY 0.680851 (-690 2460);
PAINT MONO (-690 2460);
FORCEPROP 0 LASTPIN (-700 2500) $PN 21
J 0
(-690 2510);
DISPLAY 0.680851 (-690 2510);
PAINT MONO (-690 2510);
FORCEPROP 0 LASTPIN (-700 2550) $PN 24
J 0
(-690 2560);
DISPLAY 0.680851 (-690 2560);
PAINT MONO (-690 2560);
FORCEPROP 0 LASTPIN (-700 2600) $PN 26
J 0
(-690 2610);
DISPLAY 0.680851 (-690 2610);
PAINT MONO (-690 2610);
FORCEPROP 0 LASTPIN (-700 2650) $PN 28
J 0
(-690 2660);
DISPLAY 0.680851 (-690 2660);
PAINT MONO (-690 2660);
FORCEPROP 0 LASTPIN (-700 2700) $PN 30
J 0
(-690 2710);
DISPLAY 0.680851 (-690 2710);
PAINT MONO (-690 2710);
FORCEPROP 0 LASTPIN (-700 2750) $PN 32
J 0
(-690 2760);
DISPLAY 0.680851 (-690 2760);
PAINT MONO (-690 2760);
FORCEPROP 0 LASTPIN (-700 2800) $PN 35
J 0
(-690 2810);
DISPLAY 0.680851 (-690 2810);
PAINT MONO (-690 2810);
FORCEPROP 0 LASTPIN (-700 2850) $PN 37
J 0
(-690 2860);
DISPLAY 0.680851 (-690 2860);
PAINT MONO (-690 2860);
FORCEPROP 0 LASTPIN (-700 2900) $PN 39
J 0
(-690 2910);
DISPLAY 0.680851 (-690 2910);
PAINT MONO (-690 2910);
FORCEPROP 0 LASTPIN (-700 2950) $PN 41
J 0
(-690 2960);
DISPLAY 0.680851 (-690 2960);
PAINT MONO (-690 2960);
FORCEPROP 0 LASTPIN (-700 3000) $PN 43
J 0
(-690 3010);
DISPLAY 0.680851 (-690 3010);
PAINT MONO (-690 3010);
FORCEPROP 0 LASTPIN (-700 3050) $PN 46
J 0
(-690 3060);
DISPLAY 0.680851 (-690 3060);
PAINT MONO (-690 3060);
FORCEPROP 0 LASTPIN (-700 3100) $PN 48
J 0
(-690 3110);
DISPLAY 0.680851 (-690 3110);
PAINT MONO (-690 3110);
FORCEPROP 0 LASTPIN (-700 3150) $PN 50
J 0
(-690 3160);
DISPLAY 0.680851 (-690 3160);
PAINT MONO (-690 3160);
FORCEPROP 0 LASTPIN (-700 3200) $PN 52
J 0
(-690 3210);
DISPLAY 0.680851 (-690 3210);
PAINT MONO (-690 3210);
FORCEPROP 0 LASTPIN (-700 3250) $PN 54
J 0
(-690 3260);
DISPLAY 0.680851 (-690 3260);
PAINT MONO (-690 3260);
FORCEPROP 0 LASTPIN (-700 3300) $PN 57
J 0
(-690 3310);
DISPLAY 0.680851 (-690 3310);
PAINT MONO (-690 3310);
FORCEPROP 0 LASTPIN (-700 3350) $PN 59
J 0
(-690 3360);
DISPLAY 0.680851 (-690 3360);
PAINT MONO (-690 3360);
FORCEPROP 0 LASTPIN (-700 3400) $PN 61
J 0
(-690 3410);
DISPLAY 0.680851 (-690 3410);
PAINT MONO (-690 3410);
FORCEPROP 0 LASTPIN (-700 3450) $PN 63
J 0
(-690 3460);
DISPLAY 0.680851 (-690 3460);
PAINT MONO (-690 3460);
FORCEPROP 0 LASTPIN (-700 3500) $PN 65
J 0
(-690 3510);
DISPLAY 0.680851 (-690 3510);
PAINT MONO (-690 3510);
FORCEPROP 0 LASTPIN (-700 3550) $PN 67
J 0
(-690 3560);
DISPLAY 0.680851 (-690 3560);
PAINT MONO (-690 3560);
FORCEPROP 0 LASTPIN (-700 3600) $PN 69
J 0
(-690 3610);
DISPLAY 0.680851 (-690 3610);
PAINT MONO (-690 3610);
FORCEPROP 0 LASTPIN (-700 3650) $PN 71
J 0
(-690 3660);
DISPLAY 0.680851 (-690 3660);
PAINT MONO (-690 3660);
FORCEPROP 0 LASTPIN (-700 3700) $PN 73
J 0
(-690 3710);
DISPLAY 0.680851 (-690 3710);
PAINT MONO (-690 3710);
FORCEPROP 0 LASTPIN (-700 3750) $PN 75
J 0
(-690 3760);
DISPLAY 0.680851 (-690 3760);
PAINT MONO (-690 3760);
FORCEPROP 0 LASTPIN (-700 3800) $PN 77
J 0
(-690 3810);
DISPLAY 0.680851 (-690 3810);
PAINT MONO (-690 3810);
FORCEPROP 0 LASTPIN (-700 3850) $PN 79
J 0
(-690 3860);
DISPLAY 0.680851 (-690 3860);
PAINT MONO (-690 3860);
FORCEPROP 0 LASTPIN (-700 3900) $PN 81
J 0
(-690 3910);
DISPLAY 0.680851 (-690 3910);
PAINT MONO (-690 3910);
FORCEPROP 0 LASTPIN (-700 3950) $PN 83
J 0
(-690 3960);
DISPLAY 0.680851 (-690 3960);
PAINT MONO (-690 3960);
FORCEPROP 0 LASTPIN (-700 4000) $PN 85
J 0
(-690 4010);
DISPLAY 0.680851 (-690 4010);
PAINT MONO (-690 4010);
FORCEPROP 0 LASTPIN (-700 4050) $PN 88
J 0
(-690 4060);
DISPLAY 0.680851 (-690 4060);
PAINT MONO (-690 4060);
FORCEPROP 0 LASTPIN (-700 4100) $PN 90
J 0
(-690 4110);
DISPLAY 0.680851 (-690 4110);
PAINT MONO (-690 4110);
FORCEPROP 0 LASTPIN (-700 4150) $PN 92
J 0
(-690 4160);
DISPLAY 0.680851 (-690 4160);
PAINT MONO (-690 4160);
FORCEPROP 0 LASTPIN (-700 4200) $PN 95
J 0
(-690 4210);
DISPLAY 0.680851 (-690 4210);
PAINT MONO (-690 4210);
FORCEPROP 0 LASTPIN (-700 4250) $PN 97
J 0
(-690 4260);
DISPLAY 0.680851 (-690 4260);
PAINT MONO (-690 4260);
FORCEPROP 0 LASTPIN (-700 4300) $PN 99
J 0
(-690 4310);
DISPLAY 0.680851 (-690 4310);
PAINT MONO (-690 4310);
FORCEPROP 0 LASTPIN (-700 4350) $PN 101
J 0
(-690 4360);
DISPLAY 0.680851 (-690 4360);
PAINT MONO (-690 4360);
FORCEPROP 0 LASTPIN (-700 4400) $PN 103
J 0
(-690 4410);
DISPLAY 0.680851 (-690 4410);
PAINT MONO (-690 4410);
FORCEPROP 0 LASTPIN (-700 4450) $PN 106
J 0
(-690 4460);
DISPLAY 0.680851 (-690 4460);
PAINT MONO (-690 4460);
FORCEPROP 0 LASTPIN (-700 4500) $PN 108
J 0
(-690 4510);
DISPLAY 0.680851 (-690 4510);
PAINT MONO (-690 4510);
FORCEPROP 0 LASTPIN (-700 4550) $PN 110
J 0
(-690 4560);
DISPLAY 0.680851 (-690 4560);
PAINT MONO (-690 4560);
FORCEPROP 0 LASTPIN (-700 4600) $PN 112
J 0
(-690 4610);
DISPLAY 0.680851 (-690 4610);
PAINT MONO (-690 4610);
FORCEPROP 0 LASTPIN (-700 4650) $PN 114
J 0
(-690 4660);
DISPLAY 0.680851 (-690 4660);
PAINT MONO (-690 4660);
FORCEPROP 0 LASTPIN (-700 4700) $PN 117
J 0
(-690 4710);
DISPLAY 0.680851 (-690 4710);
PAINT MONO (-690 4710);
FORCEPROP 0 LASTPIN (-700 4750) $PN 119
J 0
(-690 4760);
DISPLAY 0.680851 (-690 4760);
PAINT MONO (-690 4760);
FORCEPROP 0 LASTPIN (-700 4800) $PN 121
J 0
(-690 4810);
DISPLAY 0.680851 (-690 4810);
PAINT MONO (-690 4810);
FORCEPROP 0 LASTPIN (-700 4850) $PN 123
J 0
(-690 4860);
DISPLAY 0.680851 (-690 4860);
PAINT MONO (-690 4860);
FORCEPROP 0 LASTPIN (-700 4900) $PN 125
J 0
(-690 4910);
DISPLAY 0.680851 (-690 4910);
PAINT MONO (-690 4910);
FORCEPROP 0 LASTPIN (-700 4950) $PN 128
J 0
(-690 4960);
DISPLAY 0.680851 (-690 4960);
PAINT MONO (-690 4960);
FORCEPROP 0 LASTPIN (-700 5000) $PN 130
J 0
(-690 5010);
DISPLAY 0.680851 (-690 5010);
PAINT MONO (-690 5010);
FORCEPROP 0 LASTPIN (-700 5050) $PN 132
J 0
(-690 5060);
DISPLAY 0.680851 (-690 5060);
PAINT MONO (-690 5060);
FORCEPROP 0 LASTPIN (-700 5100) $PN 134
J 0
(-690 5110);
DISPLAY 0.680851 (-690 5110);
PAINT MONO (-690 5110);
FORCEPROP 0 LASTPIN (-700 5150) $PN 136
J 0
(-690 5160);
DISPLAY 0.680851 (-690 5160);
PAINT MONO (-690 5160);
FORCEPROP 0 LASTPIN (-700 5200) $PN 139
J 0
(-690 5210);
DISPLAY 0.680851 (-690 5210);
PAINT MONO (-690 5210);
FORCEPROP 0 LASTPIN (-700 5250) $PN 141
J 0
(-690 5260);
DISPLAY 0.680851 (-690 5260);
PAINT MONO (-690 5260);
FORCEPROP 0 LASTPIN (-700 5300) $PN 143
J 0
(-690 5310);
DISPLAY 0.680851 (-690 5310);
PAINT MONO (-690 5310);
FORCEPROP 0 LASTPIN (-1900 2050) $PN 151
J 2
(-1910 2060);
DISPLAY 0.680851 (-1910 2060);
PAINT MONO (-1910 2060);
FORCEPROP 0 LASTPIN (-1900 2100) $PN 153
J 2
(-1910 2110);
DISPLAY 0.680851 (-1910 2110);
PAINT MONO (-1910 2110);
FORCEPROP 0 LASTPIN (-1900 2150) $PN 155
J 2
(-1910 2160);
DISPLAY 0.680851 (-1910 2160);
PAINT MONO (-1910 2160);
FORCEPROP 0 LASTPIN (-1900 2200) $PN 158
J 2
(-1910 2210);
DISPLAY 0.680851 (-1910 2210);
PAINT MONO (-1910 2210);
FORCEPROP 0 LASTPIN (-1900 2250) $PN 160
J 2
(-1910 2260);
DISPLAY 0.680851 (-1910 2260);
PAINT MONO (-1910 2260);
FORCEPROP 0 LASTPIN (-1900 2300) $PN 162
J 2
(-1910 2310);
DISPLAY 0.680851 (-1910 2310);
PAINT MONO (-1910 2310);
FORCEPROP 0 LASTPIN (-1900 2350) $PN 164
J 2
(-1910 2360);
DISPLAY 0.680851 (-1910 2360);
PAINT MONO (-1910 2360);
FORCEPROP 0 LASTPIN (-1900 2400) $PN 166
J 2
(-1910 2410);
DISPLAY 0.680851 (-1910 2410);
PAINT MONO (-1910 2410);
FORCEPROP 0 LASTPIN (-1900 2450) $PN 169
J 2
(-1910 2460);
DISPLAY 0.680851 (-1910 2460);
PAINT MONO (-1910 2460);
FORCEPROP 0 LASTPIN (-1900 2500) $PN 171
J 2
(-1910 2510);
DISPLAY 0.680851 (-1910 2510);
PAINT MONO (-1910 2510);
FORCEPROP 0 LASTPIN (-1900 2550) $PN 173
J 2
(-1910 2560);
DISPLAY 0.680851 (-1910 2560);
PAINT MONO (-1910 2560);
FORCEPROP 0 LASTPIN (-1900 2600) $PN 175
J 2
(-1910 2610);
DISPLAY 0.680851 (-1910 2610);
PAINT MONO (-1910 2610);
FORCEPROP 0 LASTPIN (-1900 2650) $PN 177
J 2
(-1910 2660);
DISPLAY 0.680851 (-1910 2660);
PAINT MONO (-1910 2660);
FORCEPROP 0 LASTPIN (-1900 2700) $PN 180
J 2
(-1910 2710);
DISPLAY 0.680851 (-1910 2710);
PAINT MONO (-1910 2710);
FORCEPROP 0 LASTPIN (-1900 2750) $PN 182
J 2
(-1910 2760);
DISPLAY 0.680851 (-1910 2760);
PAINT MONO (-1910 2760);
FORCEPROP 0 LASTPIN (-1900 2800) $PN 184
J 2
(-1910 2810);
DISPLAY 0.680851 (-1910 2810);
PAINT MONO (-1910 2810);
FORCEPROP 0 LASTPIN (-1900 2850) $PN 186
J 2
(-1910 2860);
DISPLAY 0.680851 (-1910 2860);
PAINT MONO (-1910 2860);
FORCEPROP 0 LASTPIN (-1900 2900) $PN 188
J 2
(-1910 2910);
DISPLAY 0.680851 (-1910 2910);
PAINT MONO (-1910 2910);
FORCEPROP 0 LASTPIN (-1900 2950) $PN 191
J 2
(-1910 2960);
DISPLAY 0.680851 (-1910 2960);
PAINT MONO (-1910 2960);
FORCEPROP 0 LASTPIN (-1900 3000) $PN 193
J 2
(-1910 3010);
DISPLAY 0.680851 (-1910 3010);
PAINT MONO (-1910 3010);
FORCEPROP 0 LASTPIN (-1900 3050) $PN 195
J 2
(-1910 3060);
DISPLAY 0.680851 (-1910 3060);
PAINT MONO (-1910 3060);
FORCEPROP 0 LASTPIN (-1900 3100) $PN 197
J 2
(-1910 3110);
DISPLAY 0.680851 (-1910 3110);
PAINT MONO (-1910 3110);
FORCEPROP 0 LASTPIN (-1900 3150) $PN 199
J 2
(-1910 3160);
DISPLAY 0.680851 (-1910 3160);
PAINT MONO (-1910 3160);
FORCEPROP 0 LASTPIN (-1900 3200) $PN 202
J 2
(-1910 3210);
DISPLAY 0.680851 (-1910 3210);
PAINT MONO (-1910 3210);
FORCEPROP 0 LASTPIN (-1900 3250) $PN 204
J 2
(-1910 3260);
DISPLAY 0.680851 (-1910 3260);
PAINT MONO (-1910 3260);
FORCEPROP 0 LASTPIN (-1900 3300) $PN 206
J 2
(-1910 3310);
DISPLAY 0.680851 (-1910 3310);
PAINT MONO (-1910 3310);
FORCEPROP 0 LASTPIN (-1900 3350) $PN 208
J 2
(-1910 3360);
DISPLAY 0.680851 (-1910 3360);
PAINT MONO (-1910 3360);
FORCEPROP 0 LASTPIN (-1900 3400) $PN 210
J 2
(-1910 3410);
DISPLAY 0.680851 (-1910 3410);
PAINT MONO (-1910 3410);
FORCEPROP 0 LASTPIN (-1900 3450) $PN 212
J 2
(-1910 3460);
DISPLAY 0.680851 (-1910 3460);
PAINT MONO (-1910 3460);
FORCEPROP 0 LASTPIN (-1900 3500) $PN 214
J 2
(-1910 3510);
DISPLAY 0.680851 (-1910 3510);
PAINT MONO (-1910 3510);
FORCEPROP 0 LASTPIN (-1900 3550) $PN 216
J 2
(-1910 3560);
DISPLAY 0.680851 (-1910 3560);
PAINT MONO (-1910 3560);
FORCEPROP 0 LASTPIN (-1900 3600) $PN 219
J 2
(-1910 3610);
DISPLAY 0.680851 (-1910 3610);
PAINT MONO (-1910 3610);
FORCEPROP 0 LASTPIN (-1900 3650) $PN 222
J 2
(-1910 3660);
DISPLAY 0.680851 (-1910 3660);
PAINT MONO (-1910 3660);
FORCEPROP 0 LASTPIN (-1900 3700) $PN 224
J 2
(-1910 3710);
DISPLAY 0.680851 (-1910 3710);
PAINT MONO (-1910 3710);
FORCEPROP 0 LASTPIN (-1900 3750) $PN 226
J 2
(-1910 3760);
DISPLAY 0.680851 (-1910 3760);
PAINT MONO (-1910 3760);
FORCEPROP 0 LASTPIN (-1900 3800) $PN 228
J 2
(-1910 3810);
DISPLAY 0.680851 (-1910 3810);
PAINT MONO (-1910 3810);
FORCEPROP 0 LASTPIN (-1900 3850) $PN 230
J 2
(-1910 3860);
DISPLAY 0.680851 (-1910 3860);
PAINT MONO (-1910 3860);
FORCEPROP 0 LASTPIN (-1900 3900) $PN 233
J 2
(-1910 3910);
DISPLAY 0.680851 (-1910 3910);
PAINT MONO (-1910 3910);
FORCEPROP 0 LASTPIN (-1900 3950) $PN 235
J 2
(-1910 3960);
DISPLAY 0.680851 (-1910 3960);
PAINT MONO (-1910 3960);
FORCEPROP 0 LASTPIN (-1900 4000) $PN 237
J 2
(-1910 4010);
DISPLAY 0.680851 (-1910 4010);
PAINT MONO (-1910 4010);
FORCEPROP 0 LASTPIN (-1900 4050) $PN 240
J 2
(-1910 4060);
DISPLAY 0.680851 (-1910 4060);
PAINT MONO (-1910 4060);
FORCEPROP 0 LASTPIN (-1900 4100) $PN 242
J 2
(-1910 4110);
DISPLAY 0.680851 (-1910 4110);
PAINT MONO (-1910 4110);
FORCEPROP 0 LASTPIN (-1900 4150) $PN 244
J 2
(-1910 4160);
DISPLAY 0.680851 (-1910 4160);
PAINT MONO (-1910 4160);
FORCEPROP 0 LASTPIN (-1900 4200) $PN 246
J 2
(-1910 4210);
DISPLAY 0.680851 (-1910 4210);
PAINT MONO (-1910 4210);
FORCEPROP 0 LASTPIN (-1900 4250) $PN 248
J 2
(-1910 4260);
DISPLAY 0.680851 (-1910 4260);
PAINT MONO (-1910 4260);
FORCEPROP 0 LASTPIN (-1900 4300) $PN 251
J 2
(-1910 4310);
DISPLAY 0.680851 (-1910 4310);
PAINT MONO (-1910 4310);
FORCEPROP 0 LASTPIN (-1900 4350) $PN 253
J 2
(-1910 4360);
DISPLAY 0.680851 (-1910 4360);
PAINT MONO (-1910 4360);
FORCEPROP 0 LASTPIN (-1900 4400) $PN 255
J 2
(-1910 4410);
DISPLAY 0.680851 (-1910 4410);
PAINT MONO (-1910 4410);
FORCEPROP 0 LASTPIN (-1900 4450) $PN 257
J 2
(-1910 4460);
DISPLAY 0.680851 (-1910 4460);
PAINT MONO (-1910 4460);
FORCEPROP 0 LASTPIN (-1900 4500) $PN 259
J 2
(-1910 4510);
DISPLAY 0.680851 (-1910 4510);
PAINT MONO (-1910 4510);
FORCEPROP 0 LASTPIN (-1900 4550) $PN 262
J 2
(-1910 4560);
DISPLAY 0.680851 (-1910 4560);
PAINT MONO (-1910 4560);
FORCEPROP 0 LASTPIN (-1900 4600) $PN 264
J 2
(-1910 4610);
DISPLAY 0.680851 (-1910 4610);
PAINT MONO (-1910 4610);
FORCEPROP 0 LASTPIN (-1900 4650) $PN 266
J 2
(-1910 4660);
DISPLAY 0.680851 (-1910 4660);
PAINT MONO (-1910 4660);
FORCEPROP 0 LASTPIN (-1900 4700) $PN 268
J 2
(-1910 4710);
DISPLAY 0.680851 (-1910 4710);
PAINT MONO (-1910 4710);
FORCEPROP 0 LASTPIN (-1900 4750) $PN 270
J 2
(-1910 4760);
DISPLAY 0.680851 (-1910 4760);
PAINT MONO (-1910 4760);
FORCEPROP 0 LASTPIN (-1900 4800) $PN 273
J 2
(-1910 4810);
DISPLAY 0.680851 (-1910 4810);
PAINT MONO (-1910 4810);
FORCEPROP 0 LASTPIN (-1900 4850) $PN 275
J 2
(-1910 4860);
DISPLAY 0.680851 (-1910 4860);
PAINT MONO (-1910 4860);
FORCEPROP 0 LASTPIN (-1900 4900) $PN 277
J 2
(-1910 4910);
DISPLAY 0.680851 (-1910 4910);
PAINT MONO (-1910 4910);
FORCEPROP 0 LASTPIN (-1900 4950) $PN 279
J 2
(-1910 4960);
DISPLAY 0.680851 (-1910 4960);
PAINT MONO (-1910 4960);
FORCEPROP 0 LASTPIN (-1900 5000) $PN 281
J 2
(-1910 5010);
DISPLAY 0.680851 (-1910 5010);
PAINT MONO (-1910 5010);
FORCEPROP 0 LASTPIN (-1900 5050) $PN 284
J 2
(-1910 5060);
DISPLAY 0.680851 (-1910 5060);
PAINT MONO (-1910 5060);
FORCEPROP 0 LASTPIN (-1900 5100) $PN 286
J 2
(-1910 5110);
DISPLAY 0.680851 (-1910 5110);
PAINT MONO (-1910 5110);
FORCEPROP 0 LASTPIN (-1900 5150) $PN 288
J 2
(-1910 5160);
DISPLAY 0.680851 (-1910 5160);
PAINT MONO (-1910 5160);
FORCEPROP 2 LAST PART_TYPE SMLF
J 0
(-1750 5725);
DISPLAY 1.021277 (-1750 5725);
FORCEPROP 1 LAST MATERIAL IO
J 0
(-1750 5475);
DISPLAY 0.468085 (-1750 5475);
PAINT SKYBLUE (-1750 5475);
FORCEPROP 2 LAST VALUE SCONN288_DDR506112002KQ
J 0
(-1750 5675);
DISPLAY 0.489362 (-1750 5675);
PAINT SKYBLUE (-1750 5675);
FORCEPROP 1 LAST PART_NUMBER DFHST8FS479
J 0
(-1750 5550);
DISPLAY 0.468085 (-1750 5550);
PAINT SKYBLUE (-1750 5550);
FORCEPROP 1 LAST CDS_LMAN_SYM_OUTLINE -450,1800,450,-1750
J 0
(-1300 3650);
DISPLAY 0.468085 (-1300 3650);
PAINT GREEN (-1300 3650);
DISPLAY INVISIBLE (-1300 3650);
FORCEPROP 1 LAST PATH I177
J 0
(-1300 3650);
DISPLAY 0.723404 (-1300 3650);
PAINT GREEN (-1300 3650);
DISPLAY INVISIBLE (-1300 3650);
FORCEPROP 1 LAST NEEDS_NO_SIZE TRUE
J 0
(-1300 3650);
DISPLAY 0.723404 (-1300 3650);
PAINT GREEN (-1300 3650);
DISPLAY INVISIBLE (-1300 3650);
FORCEPROP 2 LAST CDS_LIB pure_quanta
J 0
(-1300 3650);
DISPLAY INVISIBLE (-1300 3650);
FORCEADD OFFPAGE..5
(-8175 3000);
FORCEPROP 2 LAST $XR0 17 
J 0
(-8429 3000);
DISPLAY 0.638298 (-8429 3000);
PAINT MONO (-8429 3000);
FORCEPROP 2 LAST PATH I178
J 0
(-8125 3075);
DISPLAY 1.021277 (-8125 3075);
DISPLAY INVISIBLE (-8125 3075);
FORCEPROP 1 LAST COMMENT_BODY TRUE
J 0
(-8075 2925);
DISPLAY 0.872340 (-8075 2925);
PAINT GREEN (-8075 2925);
DISPLAY INVISIBLE (-8075 2925);
FORCEPROP 1 LAST OFFPAGE TRUE
J 0
(-7850 2875);
DISPLAY 0.872340 (-7850 2875);
PAINT GREEN (-7850 2875);
DISPLAY INVISIBLE (-7850 2875);
FORCEPROP 2 LAST CDS_LIB mstr_standard
J 0
(-8175 3000);
DISPLAY INVISIBLE (-8175 3000);
FORCEADD OFFPAGE..1
(-8325 4350);
FORCEPROP 2 LAST $XR0 17 
J 0
(-8546 4350);
DISPLAY 0.638298 (-8546 4350);
PAINT MONO (-8546 4350);
FORCEPROP 2 LAST PATH I18
J 0
(-8275 4425);
DISPLAY 1.021277 (-8275 4425);
DISPLAY INVISIBLE (-8275 4425);
FORCEPROP 1 LAST COMMENT_BODY TRUE
J 0
(-8200 4250);
DISPLAY 0.872340 (-8200 4250);
PAINT GREEN (-8200 4250);
DISPLAY INVISIBLE (-8200 4250);
FORCEPROP 1 LAST OFFPAGE TRUE
J 0
(-8000 4225);
DISPLAY 0.872340 (-8000 4225);
PAINT GREEN (-8000 4225);
DISPLAY INVISIBLE (-8000 4225);
FORCEPROP 2 LAST CDS_LIB mstr_standard
J 0
(-8325 4350);
DISPLAY 0.808511 (-8325 4350);
DISPLAY INVISIBLE (-8325 4350);
FORCEADD OFFPAGE..6
(-8325 2800);
FORCEPROP 2 LAST $XR5 136 
J 0
(-9054 2800);
DISPLAY 0.638298 (-9054 2800);
PAINT MONO (-9054 2800);
FORCEPROP 2 LAST $XR4 96 
J 0
(-8934 2800);
DISPLAY 0.638298 (-8934 2800);
PAINT MONO (-8934 2800);
FORCEPROP 2 LAST $XR3 95 
J 0
(-8844 2800);
DISPLAY 0.638298 (-8844 2800);
PAINT MONO (-8844 2800);
FORCEPROP 2 LAST $XR2 94 
J 0
(-8754 2800);
DISPLAY 0.638298 (-8754 2800);
PAINT MONO (-8754 2800);
FORCEPROP 2 LAST $XR1 93 
J 0
(-8664 2800);
DISPLAY 0.638298 (-8664 2800);
PAINT MONO (-8664 2800);
FORCEPROP 2 LAST $XR0 91 
J 0
(-8574 2800);
DISPLAY 0.638298 (-8574 2800);
PAINT MONO (-8574 2800);
FORCEPROP 2 LAST PATH I180
J 0
(-8625 2850);
DISPLAY 1.021277 (-8625 2850);
DISPLAY INVISIBLE (-8625 2850);
FORCEPROP 1 LAST COMMENT_BODY TRUE
J 0
(-8225 2725);
DISPLAY 0.872340 (-8225 2725);
PAINT GREEN (-8225 2725);
DISPLAY INVISIBLE (-8225 2725);
FORCEPROP 1 LAST OFFPAGE TRUE
J 0
(-8000 2675);
DISPLAY 0.872340 (-8000 2675);
PAINT GREEN (-8000 2675);
DISPLAY INVISIBLE (-8000 2675);
FORCEPROP 2 LAST CDS_LIB mstr_standard
J 0
(-8325 2800);
DISPLAY 0.808511 (-8325 2800);
DISPLAY INVISIBLE (-8325 2800);
FORCEADD Q_CAP..1
R 2
(-8650 3175);
FORCEPROP 1 LAST LOCATION C116
J 2
(-8700 3275);
DISPLAY 0.489362 (-8700 3275);
PAINT SKYBLUE (-8700 3275);
FORCEPROP 0 LAST $SEC 1
J 0
(-8700 3325);
DISPLAY 0.680851 (-8700 3325);
PAINT MONO (-8700 3325);
DISPLAY INVISIBLE (-8700 3325);
FORCEPROP 0 LAST CDS_SEC 1
J 0
(-8700 3325);
DISPLAY 1.021277 (-8700 3325);
DISPLAY INVISIBLE (-8700 3325);
FORCEPROP 1 LASTPIN (-8650 3275) $PN 1
J 2
(-8660 3255);
DISPLAY 0.489362 (-8660 3255);
PAINT MONO (-8660 3255);
FORCEPROP 1 LASTPIN (-8650 3075) $PN 2
J 2
(-8660 3055);
DISPLAY 0.489362 (-8660 3055);
PAINT MONO (-8660 3055);
FORCEPROP 1 LAST MATERIAL X7R
J 2
(-8700 3075);
DISPLAY 0.489362 (-8700 3075);
PAINT SKYBLUE (-8700 3075);
FORCEPROP 1 LAST TOLERANCE 10%
J 2
(-8700 3125);
DISPLAY 0.489362 (-8700 3125);
PAINT SKYBLUE (-8700 3125);
FORCEPROP 1 LAST VALUE 0.1UF
J 2
(-8700 3225);
DISPLAY 0.489362 (-8700 3225);
PAINT SKYBLUE (-8700 3225);
FORCEPROP 1 LAST VOLTAGE 25V
J 2
(-8700 3175);
DISPLAY 0.489362 (-8700 3175);
PAINT SKYBLUE (-8700 3175);
FORCEPROP 1 LAST PART_NUMBER CH4104K1B00
J 2
(-8700 3025);
DISPLAY 0.489362 (-8700 3025);
PAINT SKYBLUE (-8700 3025);
FORCEPROP 1 LAST PACK_TYPE 0402
J 2
(-8700 2975);
DISPLAY 0.489362 (-8700 2975);
PAINT SKYBLUE (-8700 2975);
FORCEPROP 0 LAST BOM_COST MEM
J 2
(-8705 3320);
DISPLAY 0.595745 (-8705 3320);
PAINT MONO (-8705 3320);
DISPLAY INVISIBLE (-8705 3320);
FORCEPROP 2 LAST CDS_LIB pure_quanta
J 0
(-8650 3175);
DISPLAY INVISIBLE (-8650 3175);
FORCEPROP 1 LAST PATH I186
J 2
(-8700 3325);
DISPLAY 0.978723 (-8700 3325);
PAINT WHITE (-8700 3325);
DISPLAY INVISIBLE (-8700 3325);
FORCEPROP 0 LAST ROOM MEM_CH_A_CPU0_DIMM1
J 2
(-8705 3320);
DISPLAY 0.595745 (-8705 3320);
PAINT RED (-8705 3320);
DISPLAY INVISIBLE (-8705 3320);
FORCEADD GND..1
(-8650 2950);
FORCEPROP 3 LASTPIN (-8650 3000) SIG_NAME GND\g
J 0
(-8640 3010);
DISPLAY 0.659574 (-8640 3010);
PAINT MONO (-8640 3010);
DISPLAY INVISIBLE (-8640 3010);
FORCEPROP 2 LAST BOM_COST MEM
J 0
(-8625 3075);
DISPLAY 0.659574 (-8625 3075);
DISPLAY INVISIBLE (-8625 3075);
FORCEPROP 1 LAST SIZE 1B
J 0
(-8575 2900);
DISPLAY 0.723404 (-8575 2900);
PAINT GREEN (-8575 2900);
DISPLAY INVISIBLE (-8575 2900);
FORCEPROP 2 LAST CDS_LIB mstr_symbols
J 0
(-8650 2950);
DISPLAY 0.808511 (-8650 2950);
DISPLAY INVISIBLE (-8650 2950);
FORCEPROP 1 LAST BODY_TYPE PLUMBING
J 0
(-8695 2907);
DISPLAY 0.276596 (-8695 2907);
PAINT GREEN (-8695 2907);
DISPLAY INVISIBLE (-8695 2907);
FORCEPROP 1 LAST PATH I187
J 0
(-8575 2950);
DISPLAY 0.872340 (-8575 2950);
PAINT AQUA (-8575 2950);
DISPLAY INVISIBLE (-8575 2950);
FORCEPROP 1 LAST VOLTAGE 0
J 0
(-8670 3045);
DISPLAY 0.829787 (-8670 3045);
PAINT SKYBLUE (-8670 3045);
DISPLAY INVISIBLE (-8670 3045);
FORCEPROP 2 LAST ROOM MEM_EFGH_DECOUPLING_CAPS
J 0
(-8625 3025);
DISPLAY 0.659574 (-8625 3025);
PAINT RED (-8625 3025);
DISPLAY INVISIBLE (-8625 3025);
FORCEPROP 1 LAST HDL_POWER GND
J 0
(-8650 3100);
DISPLAY 0.723404 (-8650 3100);
PAINT GREEN (-8650 3100);
DISPLAY INVISIBLE (-8650 3100);
FORCEADD OFFPAGE..6
(-9075 2100);
FORCEPROP 2 LAST $XR5 81 
J 0
(-9444 2136);
DISPLAY 0.638298 (-9444 2136);
PAINT MONO (-9444 2136);
FORCEPROP 2 LAST $XR4 96 
J 0
(-9354 2136);
DISPLAY 0.638298 (-9354 2136);
PAINT MONO (-9354 2136);
FORCEPROP 2 LAST $XR3 95 
J 0
(-9444 2064);
DISPLAY 0.638298 (-9444 2064);
PAINT MONO (-9444 2064);
FORCEPROP 2 LAST $XR2 94 
J 0
(-9354 2064);
DISPLAY 0.638298 (-9354 2064);
PAINT MONO (-9354 2064);
FORCEPROP 2 LAST $XR1 93 
J 0
(-9444 2100);
DISPLAY 0.638298 (-9444 2100);
PAINT MONO (-9444 2100);
FORCEPROP 2 LAST $XR0 91 
J 0
(-9354 2100);
DISPLAY 0.638298 (-9354 2100);
PAINT MONO (-9354 2100);
FORCEPROP 2 LAST PATH I188
J 0
(-9025 2175);
DISPLAY 1.021277 (-9025 2175);
DISPLAY INVISIBLE (-9025 2175);
FORCEPROP 1 LAST COMMENT_BODY TRUE
J 0
(-8975 2025);
DISPLAY 0.872340 (-8975 2025);
PAINT GREEN (-8975 2025);
DISPLAY INVISIBLE (-8975 2025);
FORCEPROP 1 LAST OFFPAGE TRUE
J 0
(-8750 1975);
DISPLAY 0.872340 (-8750 1975);
PAINT GREEN (-8750 1975);
DISPLAY INVISIBLE (-8750 1975);
FORCEPROP 2 LAST CDS_LIB mstr_standard
J 0
(-9075 2100);
DISPLAY INVISIBLE (-9075 2100);
FORCEADD Q_RES..1
R 2
(-8525 2100);
FORCEPROP 1 LAST LOCATION R298
J 2
(-8475 2150);
DISPLAY 0.489362 (-8475 2150);
PAINT SKYBLUE (-8475 2150);
FORCEPROP 0 LAST $SEC 1
J 0
(-8475 2200);
DISPLAY 0.680851 (-8475 2200);
PAINT MONO (-8475 2200);
DISPLAY INVISIBLE (-8475 2200);
FORCEPROP 0 LAST CDS_SEC 1
J 0
(-8475 2200);
DISPLAY 1.021277 (-8475 2200);
DISPLAY INVISIBLE (-8475 2200);
FORCEPROP 1 LASTPIN (-8425 2100) $PN 1
J 2
(-8437 2112);
DISPLAY 0.489362 (-8437 2112);
PAINT MONO (-8437 2112);
FORCEPROP 1 LASTPIN (-8625 2100) $PN 2
J 2
(-8587 2112);
DISPLAY 0.489362 (-8587 2112);
PAINT MONO (-8587 2112);
FORCEPROP 1 LAST VALUE 0
J 0
(-8525 2050);
DISPLAY 0.489362 (-8525 2050);
PAINT SKYBLUE (-8525 2050);
FORCEPROP 2 LAST BOM_COST MEM
J 0
(-8550 2250);
DISPLAY 0.744681 (-8550 2250);
PAINT WHITE (-8550 2250);
DISPLAY INVISIBLE (-8550 2250);
FORCEPROP 2 LAST CDS_LIB pure_quanta
J 0
(-8525 2100);
DISPLAY INVISIBLE (-8525 2100);
FORCEPROP 1 LAST PATH I189
J 2
(-8475 2250);
DISPLAY 0.978723 (-8475 2250);
PAINT WHITE (-8475 2250);
DISPLAY INVISIBLE (-8475 2250);
FORCEPROP 1 LAST WATTAGE 1/16W
J 0
(-8450 2025);
DISPLAY 0.489362 (-8450 2025);
PAINT SKYBLUE (-8450 2025);
DISPLAY INVISIBLE (-8450 2025);
FORCEPROP 1 LAST MATERIAL CHIP
J 0
(-8700 2075);
DISPLAY 0.489362 (-8700 2075);
PAINT SKYBLUE (-8700 2075);
DISPLAY INVISIBLE (-8700 2075);
FORCEPROP 1 LAST TOLERANCE 5%
J 2
(-8400 2075);
DISPLAY 0.489362 (-8400 2075);
PAINT SKYBLUE (-8400 2075);
DISPLAY INVISIBLE (-8400 2075);
FORCEPROP 1 LAST PART_NUMBER CS00002JB38
J 0
(-8625 2150);
DISPLAY 0.489362 (-8625 2150);
PAINT SKYBLUE (-8625 2150);
DISPLAY INVISIBLE (-8625 2150);
FORCEPROP 1 LAST PACK_TYPE 0402LF
J 0
(-8700 2025);
DISPLAY 0.489362 (-8700 2025);
PAINT SKYBLUE (-8700 2025);
DISPLAY INVISIBLE (-8700 2025);
FORCEPROP 2 LAST ROOM RST_CPU0_PLD_TO_DIMM
J 0
(-8550 2200);
DISPLAY 0.744681 (-8550 2200);
PAINT RED (-8550 2200);
DISPLAY INVISIBLE (-8550 2200);
FORCEADD OFFPAGE..1
(-8325 4550);
FORCEPROP 2 LAST $XR0 17 
J 0
(-8546 4550);
DISPLAY 0.638298 (-8546 4550);
PAINT MONO (-8546 4550);
FORCEPROP 2 LAST PATH I19
J 0
(-8275 4625);
DISPLAY 1.021277 (-8275 4625);
DISPLAY INVISIBLE (-8275 4625);
FORCEPROP 1 LAST COMMENT_BODY TRUE
J 0
(-8200 4450);
DISPLAY 0.872340 (-8200 4450);
PAINT GREEN (-8200 4450);
DISPLAY INVISIBLE (-8200 4450);
FORCEPROP 1 LAST OFFPAGE TRUE
J 0
(-8000 4425);
DISPLAY 0.872340 (-8000 4425);
PAINT GREEN (-8000 4425);
DISPLAY INVISIBLE (-8000 4425);
FORCEPROP 2 LAST CDS_LIB mstr_standard
J 0
(-8325 4550);
DISPLAY 0.723404 (-8325 4550);
PAINT MONO (-8325 4550);
DISPLAY INVISIBLE (-8325 4550);
FORCEADD VCC_CORE..1
(-8400 2425);
FORCEPROP 3 LASTPIN (-8400 2375) SIG_NAME P3V3_STBY\g
J 0
(-8390 2385);
DISPLAY 0.659574 (-8390 2385);
PAINT MONO (-8390 2385);
DISPLAY INVISIBLE (-8390 2385);
FORCEPROP 1 LAST HDL_POWER P3V3_STBY
J 1
(-8400 2475);
DISPLAY 0.489362 (-8400 2475);
PAINT GREEN (-8400 2475);
FORCEPROP 2 LAST CDS_LIB mstr_symbols
J 0
(-8400 2425);
DISPLAY INVISIBLE (-8400 2425);
FORCEPROP 1 LAST PATH I190
J 0
(-8350 2450);
DISPLAY 0.872340 (-8350 2450);
PAINT AQUA (-8350 2450);
DISPLAY INVISIBLE (-8350 2450);
FORCEPROP 0 LAST VOLTAGE 3.3
J 0
(-8675 2575);
DISPLAY 1.021277 (-8675 2575);
PAINT SKYBLUE (-8675 2575);
DISPLAY INVISIBLE (-8675 2575);
FORCEPROP 2 LAST ROOM PVCCINFAON_CPU0_CTRL
J 0
(-8400 2525);
DISPLAY 0.808511 (-8400 2525);
PAINT RED (-8400 2525);
DISPLAY INVISIBLE (-8400 2525);
FORCEADD Q_RES..2
(-8400 2250);
FORCEPROP 1 LAST LOCATION R97
J 0
(-8355 2375);
DISPLAY 0.489362 (-8355 2375);
PAINT SKYBLUE (-8355 2375);
FORCEPROP 0 LAST $SEC 1
J 0
(-8350 2425);
DISPLAY 0.680851 (-8350 2425);
PAINT MONO (-8350 2425);
DISPLAY INVISIBLE (-8350 2425);
FORCEPROP 0 LAST CDS_SEC 1
J 0
(-8350 2425);
DISPLAY 1.021277 (-8350 2425);
DISPLAY INVISIBLE (-8350 2425);
FORCEPROP 1 LASTPIN (-8400 2350) $PN 1
J 0
(-8395 2312);
DISPLAY 0.489362 (-8395 2312);
PAINT MONO (-8395 2312);
FORCEPROP 1 LASTPIN (-8400 2150) $PN 2
J 0
(-8395 2160);
DISPLAY 0.489362 (-8395 2160);
PAINT MONO (-8395 2160);
FORCEPROP 1 LAST PACK_TYPE 0402LF
J 0
(-8350 2200);
DISPLAY 0.489362 (-8350 2200);
PAINT SKYBLUE (-8350 2200);
FORCEPROP 1 LAST MATERIAL EMPTY
J 0
(-8350 2250);
DISPLAY 0.489362 (-8350 2250);
PAINT RED (-8350 2250);
FORCEPROP 1 LAST WATTAGE 1/16W
J 0
(-8350 2275);
DISPLAY 0.489362 (-8350 2275);
PAINT SKYBLUE (-8350 2275);
FORCEPROP 1 LAST TOLERANCE 5%
J 0
(-8350 2300);
DISPLAY 0.489362 (-8350 2300);
PAINT SKYBLUE (-8350 2300);
FORCEPROP 1 LAST VALUE 1K
J 0
(-8355 2325);
DISPLAY 0.489362 (-8355 2325);
PAINT SKYBLUE (-8355 2325);
FORCEPROP 2 LAST BOM_COST MEM
J 0
(-8350 2425);
DISPLAY 0.808511 (-8350 2425);
DISPLAY INVISIBLE (-8350 2425);
FORCEPROP 2 LAST CDS_LIB pure_quanta
J 0
(-8400 2250);
DISPLAY INVISIBLE (-8400 2250);
FORCEPROP 1 LAST PATH I191
J 0
(-8350 2425);
DISPLAY 0.978723 (-8350 2425);
PAINT WHITE (-8350 2425);
DISPLAY INVISIBLE (-8350 2425);
FORCEPROP 1 LAST PART_NUMBER TMP_QCS21002JB34
J 0
(-8350 2225);
DISPLAY 0.489362 (-8350 2225);
PAINT SKYBLUE (-8350 2225);
DISPLAY INVISIBLE (-8350 2225);
FORCEPROP 2 LAST ROOM MEM_CH_A_CPU0_DIMM1
J 0
(-8350 2475);
DISPLAY 0.808511 (-8350 2475);
PAINT RED (-8350 2475);
DISPLAY INVISIBLE (-8350 2475);
FORCEADD OFFPAGE..2
(-2500 4350);
FORCEPROP 2 LAST $XR0 17 
J 0
(-2311 4350);
DISPLAY 0.638298 (-2311 4350);
PAINT MONO (-2311 4350);
FORCEPROP 1 LAST COMMENT_BODY TRUE
J 0
(-2545 4255);
DISPLAY 0.872340 (-2545 4255);
PAINT GREEN (-2545 4255);
DISPLAY INVISIBLE (-2545 4255);
FORCEPROP 1 LAST OFFPAGE TRUE
J 0
(-2175 4225);
DISPLAY 0.723404 (-2175 4225);
PAINT GREEN (-2175 4225);
DISPLAY INVISIBLE (-2175 4225);
FORCEPROP 2 LAST CDS_LIB mstr_standard
J 0
(-2500 4350);
DISPLAY 0.723404 (-2500 4350);
PAINT MONO (-2500 4350);
DISPLAY INVISIBLE (-2500 4350);
FORCEPROP 2 LAST PATH I193
J 0
(-2300 4400);
DISPLAY 0.680851 (-2300 4400);
DISPLAY INVISIBLE (-2300 4400);
FORCEADD OFFPAGE..2
(-2500 4400);
FORCEPROP 2 LAST $XR0 17 
J 0
(-2311 4400);
DISPLAY 0.638298 (-2311 4400);
PAINT MONO (-2311 4400);
FORCEPROP 1 LAST COMMENT_BODY TRUE
J 0
(-2545 4305);
DISPLAY 0.872340 (-2545 4305);
PAINT GREEN (-2545 4305);
DISPLAY INVISIBLE (-2545 4305);
FORCEPROP 1 LAST OFFPAGE TRUE
J 0
(-2175 4275);
DISPLAY 0.723404 (-2175 4275);
PAINT GREEN (-2175 4275);
DISPLAY INVISIBLE (-2175 4275);
FORCEPROP 2 LAST CDS_LIB mstr_standard
J 0
(-2500 4400);
DISPLAY 0.723404 (-2500 4400);
PAINT MONO (-2500 4400);
DISPLAY INVISIBLE (-2500 4400);
FORCEPROP 2 LAST PATH I194
J 0
(-2300 4450);
DISPLAY 0.680851 (-2300 4450);
DISPLAY INVISIBLE (-2300 4450);
FORCEADD OFFPAGE..2
(-2500 3300);
FORCEPROP 2 LAST $XR0 17 
J 0
(-2311 3300);
DISPLAY 0.638298 (-2311 3300);
PAINT MONO (-2311 3300);
FORCEPROP 1 LAST COMMENT_BODY TRUE
J 0
(-2545 3205);
DISPLAY 0.872340 (-2545 3205);
PAINT GREEN (-2545 3205);
DISPLAY INVISIBLE (-2545 3205);
FORCEPROP 1 LAST OFFPAGE TRUE
J 0
(-2175 3175);
DISPLAY 0.723404 (-2175 3175);
PAINT GREEN (-2175 3175);
DISPLAY INVISIBLE (-2175 3175);
FORCEPROP 2 LAST CDS_LIB mstr_standard
J 0
(-2500 3300);
DISPLAY 0.723404 (-2500 3300);
PAINT MONO (-2500 3300);
DISPLAY INVISIBLE (-2500 3300);
FORCEPROP 2 LAST PATH I195
J 0
(-2300 3350);
DISPLAY 0.680851 (-2300 3350);
DISPLAY INVISIBLE (-2300 3350);
FORCEADD OFFPAGE..2
(-2500 3350);
FORCEPROP 2 LAST $XR0 17 
J 0
(-2311 3350);
DISPLAY 0.638298 (-2311 3350);
PAINT MONO (-2311 3350);
FORCEPROP 1 LAST COMMENT_BODY TRUE
J 0
(-2545 3255);
DISPLAY 0.872340 (-2545 3255);
PAINT GREEN (-2545 3255);
DISPLAY INVISIBLE (-2545 3255);
FORCEPROP 1 LAST OFFPAGE TRUE
J 0
(-2175 3225);
DISPLAY 0.723404 (-2175 3225);
PAINT GREEN (-2175 3225);
DISPLAY INVISIBLE (-2175 3225);
FORCEPROP 2 LAST CDS_LIB mstr_standard
J 0
(-2500 3350);
DISPLAY 0.723404 (-2500 3350);
PAINT MONO (-2500 3350);
DISPLAY INVISIBLE (-2500 3350);
FORCEPROP 2 LAST PATH I196
J 0
(-2300 3400);
DISPLAY 0.680851 (-2300 3400);
DISPLAY INVISIBLE (-2300 3400);
FORCEADD TAP..1
(-3300 4300);
FORCEPROP 3 LASTPIN (-3350 4300) SIG_NAME M_H_CPU0_SA_DQS_DN<9>
J 0
(-3340 4310);
DISPLAY 0.659574 (-3340 4310);
PAINT MONO (-3340 4310);
DISPLAY INVISIBLE (-3340 4310);
FORCEPROP 1 LASTPIN (-3350 4300) BN 9
J 0
(-3362 4308);
DISPLAY 0.489362 (-3362 4308);
PAINT GREEN (-3362 4308);
FORCEPROP 2 LAST CDS_LIB mstr_standard
J 0
(-3300 4300);
DISPLAY 0.723404 (-3300 4300);
PAINT MONO (-3300 4300);
DISPLAY INVISIBLE (-3300 4300);
FORCEPROP 1 LAST BODY_TYPE PLUMBING
J 0
(-3300 4350);
DISPLAY 0.872340 (-3300 4350);
PAINT GREEN (-3300 4350);
DISPLAY INVISIBLE (-3300 4350);
FORCEPROP 1 LAST HDL_TAP TRUE
J 0
(-2975 4175);
DISPLAY 0.872340 (-2975 4175);
DISPLAY INVISIBLE (-2975 4175);
FORCEPROP 1 LAST PATH I197
J 0
(-3302 4300);
DISPLAY 0.872340 (-3302 4300);
PAINT GREEN (-3302 4300);
DISPLAY INVISIBLE (-3302 4300);
FORCEADD TAP..1
(-3300 4200);
FORCEPROP 3 LASTPIN (-3350 4200) SIG_NAME M_H_CPU0_SA_DQS_DN<8>
J 0
(-3340 4210);
DISPLAY 0.659574 (-3340 4210);
PAINT MONO (-3340 4210);
DISPLAY INVISIBLE (-3340 4210);
FORCEPROP 1 LASTPIN (-3350 4200) BN 8
J 0
(-3362 4208);
DISPLAY 0.489362 (-3362 4208);
PAINT GREEN (-3362 4208);
FORCEPROP 2 LAST CDS_LIB mstr_standard
J 0
(-3300 4200);
DISPLAY 0.723404 (-3300 4200);
PAINT MONO (-3300 4200);
DISPLAY INVISIBLE (-3300 4200);
FORCEPROP 1 LAST BODY_TYPE PLUMBING
J 0
(-3300 4250);
DISPLAY 0.872340 (-3300 4250);
PAINT GREEN (-3300 4250);
DISPLAY INVISIBLE (-3300 4250);
FORCEPROP 1 LAST HDL_TAP TRUE
J 0
(-2975 4075);
DISPLAY 0.872340 (-2975 4075);
DISPLAY INVISIBLE (-2975 4075);
FORCEPROP 1 LAST PATH I198
J 0
(-3302 4200);
DISPLAY 0.872340 (-3302 4200);
PAINT GREEN (-3302 4200);
DISPLAY INVISIBLE (-3302 4200);
FORCEADD TAP..1
(-3500 4350);
FORCEPROP 3 LASTPIN (-3550 4350) SIG_NAME M_H_CPU0_SA_DQS_DP<9>
J 0
(-3540 4360);
DISPLAY 0.659574 (-3540 4360);
PAINT MONO (-3540 4360);
DISPLAY INVISIBLE (-3540 4360);
FORCEPROP 1 LASTPIN (-3550 4350) BN 9
J 0
(-3562 4358);
DISPLAY 0.489362 (-3562 4358);
PAINT GREEN (-3562 4358);
FORCEPROP 2 LAST CDS_LIB mstr_standard
J 0
(-3500 4350);
DISPLAY 0.723404 (-3500 4350);
PAINT MONO (-3500 4350);
DISPLAY INVISIBLE (-3500 4350);
FORCEPROP 1 LAST BODY_TYPE PLUMBING
J 0
(-3500 4400);
DISPLAY 0.872340 (-3500 4400);
PAINT GREEN (-3500 4400);
DISPLAY INVISIBLE (-3500 4400);
FORCEPROP 1 LAST HDL_TAP TRUE
J 0
(-3175 4225);
DISPLAY 0.872340 (-3175 4225);
DISPLAY INVISIBLE (-3175 4225);
FORCEPROP 1 LAST PATH I199
J 0
(-3502 4350);
DISPLAY 0.872340 (-3502 4350);
PAINT GREEN (-3502 4350);
DISPLAY INVISIBLE (-3502 4350);
FORCEADD OFFPAGE..5
(-8325 1900);
FORCEPROP 2 LAST $XR0 17 
J 0
(-8549 1900);
DISPLAY 0.638298 (-8549 1900);
PAINT MONO (-8549 1900);
FORCEPROP 2 LAST PATH I2
J 0
(-8275 1975);
DISPLAY 1.021277 (-8275 1975);
DISPLAY INVISIBLE (-8275 1975);
FORCEPROP 1 LAST COMMENT_BODY TRUE
J 0
(-8225 1825);
DISPLAY 0.872340 (-8225 1825);
PAINT GREEN (-8225 1825);
DISPLAY INVISIBLE (-8225 1825);
FORCEPROP 1 LAST OFFPAGE TRUE
J 0
(-8000 1775);
DISPLAY 0.872340 (-8000 1775);
PAINT GREEN (-8000 1775);
DISPLAY INVISIBLE (-8000 1775);
FORCEPROP 2 LAST CDS_LIB mstr_standard
J 0
(-8325 1900);
DISPLAY 0.808511 (-8325 1900);
DISPLAY INVISIBLE (-8325 1900);
FORCEADD OFFPAGE..1
(-8325 5400);
FORCEPROP 2 LAST $XR0 17 
J 0
(-8546 5400);
DISPLAY 0.638298 (-8546 5400);
PAINT MONO (-8546 5400);
FORCEPROP 2 LAST PATH I20
J 0
(-8275 5475);
DISPLAY 1.021277 (-8275 5475);
DISPLAY INVISIBLE (-8275 5475);
FORCEPROP 1 LAST COMMENT_BODY TRUE
J 0
(-8200 5300);
DISPLAY 0.872340 (-8200 5300);
PAINT GREEN (-8200 5300);
DISPLAY INVISIBLE (-8200 5300);
FORCEPROP 1 LAST OFFPAGE TRUE
J 0
(-8000 5275);
DISPLAY 0.872340 (-8000 5275);
PAINT GREEN (-8000 5275);
DISPLAY INVISIBLE (-8000 5275);
FORCEPROP 2 LAST CDS_LIB mstr_standard
J 0
(-8325 5400);
DISPLAY 0.723404 (-8325 5400);
PAINT MONO (-8325 5400);
DISPLAY INVISIBLE (-8325 5400);
FORCEADD TAP..1
(-3500 4250);
FORCEPROP 3 LASTPIN (-3550 4250) SIG_NAME M_H_CPU0_SA_DQS_DP<8>
J 0
(-3540 4260);
DISPLAY 0.659574 (-3540 4260);
PAINT MONO (-3540 4260);
DISPLAY INVISIBLE (-3540 4260);
FORCEPROP 1 LASTPIN (-3550 4250) BN 8
J 0
(-3562 4258);
DISPLAY 0.489362 (-3562 4258);
PAINT GREEN (-3562 4258);
FORCEPROP 2 LAST CDS_LIB mstr_standard
J 0
(-3500 4250);
DISPLAY 0.723404 (-3500 4250);
PAINT MONO (-3500 4250);
DISPLAY INVISIBLE (-3500 4250);
FORCEPROP 1 LAST BODY_TYPE PLUMBING
J 0
(-3500 4300);
DISPLAY 0.872340 (-3500 4300);
PAINT GREEN (-3500 4300);
DISPLAY INVISIBLE (-3500 4300);
FORCEPROP 1 LAST HDL_TAP TRUE
J 0
(-3175 4125);
DISPLAY 0.872340 (-3175 4125);
DISPLAY INVISIBLE (-3175 4125);
FORCEPROP 1 LAST PATH I200
J 0
(-3502 4250);
DISPLAY 0.872340 (-3502 4250);
PAINT GREEN (-3502 4250);
DISPLAY INVISIBLE (-3502 4250);
FORCEADD TAP..1
(-3300 4100);
FORCEPROP 3 LASTPIN (-3350 4100) SIG_NAME M_H_CPU0_SA_DQS_DN<7>
J 0
(-3340 4110);
DISPLAY 0.659574 (-3340 4110);
PAINT MONO (-3340 4110);
DISPLAY INVISIBLE (-3340 4110);
FORCEPROP 1 LASTPIN (-3350 4100) BN 7
J 0
(-3362 4108);
DISPLAY 0.489362 (-3362 4108);
PAINT GREEN (-3362 4108);
FORCEPROP 2 LAST CDS_LIB mstr_standard
J 0
(-3300 4100);
DISPLAY 0.723404 (-3300 4100);
PAINT MONO (-3300 4100);
DISPLAY INVISIBLE (-3300 4100);
FORCEPROP 1 LAST BODY_TYPE PLUMBING
J 0
(-3300 4150);
DISPLAY 0.872340 (-3300 4150);
PAINT GREEN (-3300 4150);
DISPLAY INVISIBLE (-3300 4150);
FORCEPROP 1 LAST HDL_TAP TRUE
J 0
(-2975 3975);
DISPLAY 0.872340 (-2975 3975);
DISPLAY INVISIBLE (-2975 3975);
FORCEPROP 1 LAST PATH I201
J 0
(-3302 4100);
DISPLAY 0.872340 (-3302 4100);
PAINT GREEN (-3302 4100);
DISPLAY INVISIBLE (-3302 4100);
FORCEADD TAP..1
(-3300 4000);
FORCEPROP 3 LASTPIN (-3350 4000) SIG_NAME M_H_CPU0_SA_DQS_DN<6>
J 0
(-3340 4010);
DISPLAY 0.659574 (-3340 4010);
PAINT MONO (-3340 4010);
DISPLAY INVISIBLE (-3340 4010);
FORCEPROP 1 LASTPIN (-3350 4000) BN 6
J 0
(-3362 4008);
DISPLAY 0.489362 (-3362 4008);
PAINT GREEN (-3362 4008);
FORCEPROP 2 LAST CDS_LIB mstr_standard
J 0
(-3300 4000);
DISPLAY 0.723404 (-3300 4000);
PAINT MONO (-3300 4000);
DISPLAY INVISIBLE (-3300 4000);
FORCEPROP 1 LAST BODY_TYPE PLUMBING
J 0
(-3300 4050);
DISPLAY 0.872340 (-3300 4050);
PAINT GREEN (-3300 4050);
DISPLAY INVISIBLE (-3300 4050);
FORCEPROP 1 LAST HDL_TAP TRUE
J 0
(-2975 3875);
DISPLAY 0.872340 (-2975 3875);
DISPLAY INVISIBLE (-2975 3875);
FORCEPROP 1 LAST PATH I202
J 0
(-3302 4000);
DISPLAY 0.872340 (-3302 4000);
PAINT GREEN (-3302 4000);
DISPLAY INVISIBLE (-3302 4000);
FORCEADD TAP..1
(-3300 3800);
FORCEPROP 3 LASTPIN (-3350 3800) SIG_NAME M_H_CPU0_SA_DQS_DN<4>
J 0
(-3340 3810);
DISPLAY 0.659574 (-3340 3810);
PAINT MONO (-3340 3810);
DISPLAY INVISIBLE (-3340 3810);
FORCEPROP 1 LASTPIN (-3350 3800) BN 4
J 0
(-3362 3808);
DISPLAY 0.489362 (-3362 3808);
PAINT GREEN (-3362 3808);
FORCEPROP 2 LAST CDS_LIB mstr_standard
J 0
(-3300 3800);
DISPLAY 0.723404 (-3300 3800);
PAINT MONO (-3300 3800);
DISPLAY INVISIBLE (-3300 3800);
FORCEPROP 1 LAST BODY_TYPE PLUMBING
J 0
(-3300 3850);
DISPLAY 0.872340 (-3300 3850);
PAINT GREEN (-3300 3850);
DISPLAY INVISIBLE (-3300 3850);
FORCEPROP 1 LAST HDL_TAP TRUE
J 0
(-2975 3675);
DISPLAY 0.872340 (-2975 3675);
DISPLAY INVISIBLE (-2975 3675);
FORCEPROP 1 LAST PATH I203
J 0
(-3302 3800);
DISPLAY 0.872340 (-3302 3800);
PAINT GREEN (-3302 3800);
DISPLAY INVISIBLE (-3302 3800);
FORCEADD TAP..1
(-3300 3900);
FORCEPROP 3 LASTPIN (-3350 3900) SIG_NAME M_H_CPU0_SA_DQS_DN<5>
J 0
(-3340 3910);
DISPLAY 0.659574 (-3340 3910);
PAINT MONO (-3340 3910);
DISPLAY INVISIBLE (-3340 3910);
FORCEPROP 1 LASTPIN (-3350 3900) BN 5
J 0
(-3362 3908);
DISPLAY 0.489362 (-3362 3908);
PAINT GREEN (-3362 3908);
FORCEPROP 2 LAST CDS_LIB mstr_standard
J 0
(-3300 3900);
DISPLAY 0.723404 (-3300 3900);
PAINT MONO (-3300 3900);
DISPLAY INVISIBLE (-3300 3900);
FORCEPROP 1 LAST BODY_TYPE PLUMBING
J 0
(-3300 3950);
DISPLAY 0.872340 (-3300 3950);
PAINT GREEN (-3300 3950);
DISPLAY INVISIBLE (-3300 3950);
FORCEPROP 1 LAST HDL_TAP TRUE
J 0
(-2975 3775);
DISPLAY 0.872340 (-2975 3775);
DISPLAY INVISIBLE (-2975 3775);
FORCEPROP 1 LAST PATH I204
J 0
(-3302 3900);
DISPLAY 0.872340 (-3302 3900);
PAINT GREEN (-3302 3900);
DISPLAY INVISIBLE (-3302 3900);
FORCEADD TAP..1
(-3300 3700);
FORCEPROP 3 LASTPIN (-3350 3700) SIG_NAME M_H_CPU0_SA_DQS_DN<3>
J 0
(-3340 3710);
DISPLAY 0.659574 (-3340 3710);
PAINT MONO (-3340 3710);
DISPLAY INVISIBLE (-3340 3710);
FORCEPROP 1 LASTPIN (-3350 3700) BN 3
J 0
(-3362 3708);
DISPLAY 0.489362 (-3362 3708);
PAINT GREEN (-3362 3708);
FORCEPROP 2 LAST CDS_LIB mstr_standard
J 0
(-3300 3700);
DISPLAY 0.723404 (-3300 3700);
PAINT MONO (-3300 3700);
DISPLAY INVISIBLE (-3300 3700);
FORCEPROP 1 LAST BODY_TYPE PLUMBING
J 0
(-3300 3750);
DISPLAY 0.872340 (-3300 3750);
PAINT GREEN (-3300 3750);
DISPLAY INVISIBLE (-3300 3750);
FORCEPROP 1 LAST HDL_TAP TRUE
J 0
(-2975 3575);
DISPLAY 0.872340 (-2975 3575);
DISPLAY INVISIBLE (-2975 3575);
FORCEPROP 1 LAST PATH I205
J 0
(-3302 3700);
DISPLAY 0.872340 (-3302 3700);
PAINT GREEN (-3302 3700);
DISPLAY INVISIBLE (-3302 3700);
FORCEADD TAP..1
(-3500 3950);
FORCEPROP 3 LASTPIN (-3550 3950) SIG_NAME M_H_CPU0_SA_DQS_DP<5>
J 0
(-3540 3960);
DISPLAY 0.659574 (-3540 3960);
PAINT MONO (-3540 3960);
DISPLAY INVISIBLE (-3540 3960);
FORCEPROP 1 LASTPIN (-3550 3950) BN 5
J 0
(-3562 3958);
DISPLAY 0.489362 (-3562 3958);
PAINT GREEN (-3562 3958);
FORCEPROP 2 LAST CDS_LIB mstr_standard
J 0
(-3500 3950);
DISPLAY 0.723404 (-3500 3950);
PAINT MONO (-3500 3950);
DISPLAY INVISIBLE (-3500 3950);
FORCEPROP 1 LAST BODY_TYPE PLUMBING
J 0
(-3500 4000);
DISPLAY 0.872340 (-3500 4000);
PAINT GREEN (-3500 4000);
DISPLAY INVISIBLE (-3500 4000);
FORCEPROP 1 LAST HDL_TAP TRUE
J 0
(-3175 3825);
DISPLAY 0.872340 (-3175 3825);
DISPLAY INVISIBLE (-3175 3825);
FORCEPROP 1 LAST PATH I206
J 0
(-3502 3950);
DISPLAY 0.872340 (-3502 3950);
PAINT GREEN (-3502 3950);
DISPLAY INVISIBLE (-3502 3950);
FORCEADD TAP..1
(-3500 4150);
FORCEPROP 3 LASTPIN (-3550 4150) SIG_NAME M_H_CPU0_SA_DQS_DP<7>
J 0
(-3540 4160);
DISPLAY 0.659574 (-3540 4160);
PAINT MONO (-3540 4160);
DISPLAY INVISIBLE (-3540 4160);
FORCEPROP 1 LASTPIN (-3550 4150) BN 7
J 0
(-3562 4158);
DISPLAY 0.489362 (-3562 4158);
PAINT GREEN (-3562 4158);
FORCEPROP 2 LAST CDS_LIB mstr_standard
J 0
(-3500 4150);
DISPLAY 0.723404 (-3500 4150);
PAINT MONO (-3500 4150);
DISPLAY INVISIBLE (-3500 4150);
FORCEPROP 1 LAST BODY_TYPE PLUMBING
J 0
(-3500 4200);
DISPLAY 0.872340 (-3500 4200);
PAINT GREEN (-3500 4200);
DISPLAY INVISIBLE (-3500 4200);
FORCEPROP 1 LAST HDL_TAP TRUE
J 0
(-3175 4025);
DISPLAY 0.872340 (-3175 4025);
DISPLAY INVISIBLE (-3175 4025);
FORCEPROP 1 LAST PATH I207
J 0
(-3502 4150);
DISPLAY 0.872340 (-3502 4150);
PAINT GREEN (-3502 4150);
DISPLAY INVISIBLE (-3502 4150);
FORCEADD TAP..1
(-3500 4050);
FORCEPROP 3 LASTPIN (-3550 4050) SIG_NAME M_H_CPU0_SA_DQS_DP<6>
J 0
(-3540 4060);
DISPLAY 0.659574 (-3540 4060);
PAINT MONO (-3540 4060);
DISPLAY INVISIBLE (-3540 4060);
FORCEPROP 1 LASTPIN (-3550 4050) BN 6
J 0
(-3562 4058);
DISPLAY 0.489362 (-3562 4058);
PAINT GREEN (-3562 4058);
FORCEPROP 2 LAST CDS_LIB mstr_standard
J 0
(-3500 4050);
DISPLAY 0.723404 (-3500 4050);
PAINT MONO (-3500 4050);
DISPLAY INVISIBLE (-3500 4050);
FORCEPROP 1 LAST BODY_TYPE PLUMBING
J 0
(-3500 4100);
DISPLAY 0.872340 (-3500 4100);
PAINT GREEN (-3500 4100);
DISPLAY INVISIBLE (-3500 4100);
FORCEPROP 1 LAST HDL_TAP TRUE
J 0
(-3175 3925);
DISPLAY 0.872340 (-3175 3925);
DISPLAY INVISIBLE (-3175 3925);
FORCEPROP 1 LAST PATH I208
J 0
(-3502 4050);
DISPLAY 0.872340 (-3502 4050);
PAINT GREEN (-3502 4050);
DISPLAY INVISIBLE (-3502 4050);
FORCEADD TAP..1
(-3500 3850);
FORCEPROP 3 LASTPIN (-3550 3850) SIG_NAME M_H_CPU0_SA_DQS_DP<4>
J 0
(-3540 3860);
DISPLAY 0.659574 (-3540 3860);
PAINT MONO (-3540 3860);
DISPLAY INVISIBLE (-3540 3860);
FORCEPROP 1 LASTPIN (-3550 3850) BN 4
J 0
(-3562 3858);
DISPLAY 0.489362 (-3562 3858);
PAINT GREEN (-3562 3858);
FORCEPROP 2 LAST CDS_LIB mstr_standard
J 0
(-3500 3850);
DISPLAY 0.723404 (-3500 3850);
PAINT MONO (-3500 3850);
DISPLAY INVISIBLE (-3500 3850);
FORCEPROP 1 LAST BODY_TYPE PLUMBING
J 0
(-3500 3900);
DISPLAY 0.872340 (-3500 3900);
PAINT GREEN (-3500 3900);
DISPLAY INVISIBLE (-3500 3900);
FORCEPROP 1 LAST HDL_TAP TRUE
J 0
(-3175 3725);
DISPLAY 0.872340 (-3175 3725);
DISPLAY INVISIBLE (-3175 3725);
FORCEPROP 1 LAST PATH I209
J 0
(-3502 3850);
DISPLAY 0.872340 (-3502 3850);
PAINT GREEN (-3502 3850);
DISPLAY INVISIBLE (-3502 3850);
FORCEADD OFFPAGE..1
(-8325 5000);
FORCEPROP 2 LAST $XR0 17 
J 0
(-8546 5000);
DISPLAY 0.638298 (-8546 5000);
PAINT MONO (-8546 5000);
FORCEPROP 2 LAST PATH I21
J 0
(-8275 5075);
DISPLAY 1.021277 (-8275 5075);
DISPLAY INVISIBLE (-8275 5075);
FORCEPROP 1 LAST COMMENT_BODY TRUE
J 0
(-8200 4900);
DISPLAY 0.872340 (-8200 4900);
PAINT GREEN (-8200 4900);
DISPLAY INVISIBLE (-8200 4900);
FORCEPROP 1 LAST OFFPAGE TRUE
J 0
(-8000 4875);
DISPLAY 0.872340 (-8000 4875);
PAINT GREEN (-8000 4875);
DISPLAY INVISIBLE (-8000 4875);
FORCEPROP 2 LAST CDS_LIB mstr_standard
J 0
(-8325 5000);
DISPLAY 0.723404 (-8325 5000);
PAINT MONO (-8325 5000);
DISPLAY INVISIBLE (-8325 5000);
FORCEADD TAP..1
(-3500 3750);
FORCEPROP 3 LASTPIN (-3550 3750) SIG_NAME M_H_CPU0_SA_DQS_DP<3>
J 0
(-3540 3760);
DISPLAY 0.659574 (-3540 3760);
PAINT MONO (-3540 3760);
DISPLAY INVISIBLE (-3540 3760);
FORCEPROP 1 LASTPIN (-3550 3750) BN 3
J 0
(-3562 3758);
DISPLAY 0.489362 (-3562 3758);
PAINT GREEN (-3562 3758);
FORCEPROP 2 LAST CDS_LIB mstr_standard
J 0
(-3500 3750);
DISPLAY 0.723404 (-3500 3750);
PAINT MONO (-3500 3750);
DISPLAY INVISIBLE (-3500 3750);
FORCEPROP 1 LAST BODY_TYPE PLUMBING
J 0
(-3500 3800);
DISPLAY 0.872340 (-3500 3800);
PAINT GREEN (-3500 3800);
DISPLAY INVISIBLE (-3500 3800);
FORCEPROP 1 LAST HDL_TAP TRUE
J 0
(-3175 3625);
DISPLAY 0.872340 (-3175 3625);
DISPLAY INVISIBLE (-3175 3625);
FORCEPROP 1 LAST PATH I210
J 0
(-3502 3750);
DISPLAY 0.872340 (-3502 3750);
PAINT GREEN (-3502 3750);
DISPLAY INVISIBLE (-3502 3750);
FORCEADD TAP..1
(-3300 3600);
FORCEPROP 3 LASTPIN (-3350 3600) SIG_NAME M_H_CPU0_SA_DQS_DN<2>
J 0
(-3340 3610);
DISPLAY 0.659574 (-3340 3610);
PAINT MONO (-3340 3610);
DISPLAY INVISIBLE (-3340 3610);
FORCEPROP 1 LASTPIN (-3350 3600) BN 2
J 0
(-3362 3608);
DISPLAY 0.489362 (-3362 3608);
PAINT GREEN (-3362 3608);
FORCEPROP 2 LAST CDS_LIB mstr_standard
J 0
(-3300 3600);
DISPLAY 0.723404 (-3300 3600);
PAINT MONO (-3300 3600);
DISPLAY INVISIBLE (-3300 3600);
FORCEPROP 1 LAST BODY_TYPE PLUMBING
J 0
(-3300 3650);
DISPLAY 0.872340 (-3300 3650);
PAINT GREEN (-3300 3650);
DISPLAY INVISIBLE (-3300 3650);
FORCEPROP 1 LAST HDL_TAP TRUE
J 0
(-2975 3475);
DISPLAY 0.872340 (-2975 3475);
DISPLAY INVISIBLE (-2975 3475);
FORCEPROP 1 LAST PATH I211
J 0
(-3302 3600);
DISPLAY 0.872340 (-3302 3600);
PAINT GREEN (-3302 3600);
DISPLAY INVISIBLE (-3302 3600);
FORCEADD TAP..1
(-3300 3500);
FORCEPROP 3 LASTPIN (-3350 3500) SIG_NAME M_H_CPU0_SA_DQS_DN<1>
J 0
(-3340 3510);
DISPLAY 0.659574 (-3340 3510);
PAINT MONO (-3340 3510);
DISPLAY INVISIBLE (-3340 3510);
FORCEPROP 1 LASTPIN (-3350 3500) BN 1
J 0
(-3362 3508);
DISPLAY 0.489362 (-3362 3508);
PAINT GREEN (-3362 3508);
FORCEPROP 2 LAST CDS_LIB mstr_standard
J 0
(-3300 3500);
DISPLAY 0.723404 (-3300 3500);
PAINT MONO (-3300 3500);
DISPLAY INVISIBLE (-3300 3500);
FORCEPROP 1 LAST BODY_TYPE PLUMBING
J 0
(-3300 3550);
DISPLAY 0.872340 (-3300 3550);
PAINT GREEN (-3300 3550);
DISPLAY INVISIBLE (-3300 3550);
FORCEPROP 1 LAST HDL_TAP TRUE
J 0
(-2975 3375);
DISPLAY 0.872340 (-2975 3375);
DISPLAY INVISIBLE (-2975 3375);
FORCEPROP 1 LAST PATH I212
J 0
(-3302 3500);
DISPLAY 0.872340 (-3302 3500);
PAINT GREEN (-3302 3500);
DISPLAY INVISIBLE (-3302 3500);
FORCEADD TAP..1
(-3300 3400);
FORCEPROP 3 LASTPIN (-3350 3400) SIG_NAME M_H_CPU0_SA_DQS_DN<0>
J 0
(-3340 3410);
DISPLAY 0.659574 (-3340 3410);
PAINT MONO (-3340 3410);
DISPLAY INVISIBLE (-3340 3410);
FORCEPROP 1 LASTPIN (-3350 3400) BN 0
J 0
(-3362 3408);
DISPLAY 0.489362 (-3362 3408);
PAINT GREEN (-3362 3408);
FORCEPROP 2 LAST CDS_LIB mstr_standard
J 0
(-3300 3400);
DISPLAY 0.723404 (-3300 3400);
PAINT MONO (-3300 3400);
DISPLAY INVISIBLE (-3300 3400);
FORCEPROP 1 LAST BODY_TYPE PLUMBING
J 0
(-3300 3450);
DISPLAY 0.872340 (-3300 3450);
PAINT GREEN (-3300 3450);
DISPLAY INVISIBLE (-3300 3450);
FORCEPROP 1 LAST HDL_TAP TRUE
J 0
(-2975 3275);
DISPLAY 0.872340 (-2975 3275);
DISPLAY INVISIBLE (-2975 3275);
FORCEPROP 1 LAST PATH I213
J 0
(-3302 3400);
DISPLAY 0.872340 (-3302 3400);
PAINT GREEN (-3302 3400);
DISPLAY INVISIBLE (-3302 3400);
FORCEADD TAP..1
(-3300 3150);
FORCEPROP 3 LASTPIN (-3350 3150) SIG_NAME M_H_CPU0_SB_DQS_DN<8>
J 0
(-3340 3160);
DISPLAY 0.659574 (-3340 3160);
PAINT MONO (-3340 3160);
DISPLAY INVISIBLE (-3340 3160);
FORCEPROP 1 LASTPIN (-3350 3150) BN 8
J 0
(-3362 3158);
DISPLAY 0.489362 (-3362 3158);
PAINT GREEN (-3362 3158);
FORCEPROP 2 LAST CDS_LIB mstr_standard
J 0
(-3300 3150);
DISPLAY 0.723404 (-3300 3150);
PAINT MONO (-3300 3150);
DISPLAY INVISIBLE (-3300 3150);
FORCEPROP 1 LAST BODY_TYPE PLUMBING
J 0
(-3300 3200);
DISPLAY 0.872340 (-3300 3200);
PAINT GREEN (-3300 3200);
DISPLAY INVISIBLE (-3300 3200);
FORCEPROP 1 LAST HDL_TAP TRUE
J 0
(-2975 3025);
DISPLAY 0.872340 (-2975 3025);
DISPLAY INVISIBLE (-2975 3025);
FORCEPROP 1 LAST PATH I214
J 0
(-3302 3150);
DISPLAY 0.872340 (-3302 3150);
PAINT GREEN (-3302 3150);
DISPLAY INVISIBLE (-3302 3150);
FORCEADD TAP..1
(-3300 3250);
FORCEPROP 3 LASTPIN (-3350 3250) SIG_NAME M_H_CPU0_SB_DQS_DN<9>
J 0
(-3340 3260);
DISPLAY 0.659574 (-3340 3260);
PAINT MONO (-3340 3260);
DISPLAY INVISIBLE (-3340 3260);
FORCEPROP 1 LASTPIN (-3350 3250) BN 9
J 0
(-3362 3258);
DISPLAY 0.489362 (-3362 3258);
PAINT GREEN (-3362 3258);
FORCEPROP 2 LAST CDS_LIB mstr_standard
J 0
(-3300 3250);
DISPLAY 0.723404 (-3300 3250);
PAINT MONO (-3300 3250);
DISPLAY INVISIBLE (-3300 3250);
FORCEPROP 1 LAST BODY_TYPE PLUMBING
J 0
(-3300 3300);
DISPLAY 0.872340 (-3300 3300);
PAINT GREEN (-3300 3300);
DISPLAY INVISIBLE (-3300 3300);
FORCEPROP 1 LAST HDL_TAP TRUE
J 0
(-2975 3125);
DISPLAY 0.872340 (-2975 3125);
DISPLAY INVISIBLE (-2975 3125);
FORCEPROP 1 LAST PATH I215
J 0
(-3302 3250);
DISPLAY 0.872340 (-3302 3250);
PAINT GREEN (-3302 3250);
DISPLAY INVISIBLE (-3302 3250);
FORCEADD TAP..1
(-3500 3450);
FORCEPROP 3 LASTPIN (-3550 3450) SIG_NAME M_H_CPU0_SA_DQS_DP<0>
J 0
(-3540 3460);
DISPLAY 0.659574 (-3540 3460);
PAINT MONO (-3540 3460);
DISPLAY INVISIBLE (-3540 3460);
FORCEPROP 1 LASTPIN (-3550 3450) BN 0
J 0
(-3562 3458);
DISPLAY 0.489362 (-3562 3458);
PAINT GREEN (-3562 3458);
FORCEPROP 2 LAST CDS_LIB mstr_standard
J 0
(-3500 3450);
DISPLAY 0.723404 (-3500 3450);
PAINT MONO (-3500 3450);
DISPLAY INVISIBLE (-3500 3450);
FORCEPROP 1 LAST BODY_TYPE PLUMBING
J 0
(-3500 3500);
DISPLAY 0.872340 (-3500 3500);
PAINT GREEN (-3500 3500);
DISPLAY INVISIBLE (-3500 3500);
FORCEPROP 1 LAST HDL_TAP TRUE
J 0
(-3175 3325);
DISPLAY 0.872340 (-3175 3325);
DISPLAY INVISIBLE (-3175 3325);
FORCEPROP 1 LAST PATH I216
J 0
(-3502 3450);
DISPLAY 0.872340 (-3502 3450);
PAINT GREEN (-3502 3450);
DISPLAY INVISIBLE (-3502 3450);
FORCEADD TAP..1
(-3500 3650);
FORCEPROP 3 LASTPIN (-3550 3650) SIG_NAME M_H_CPU0_SA_DQS_DP<2>
J 0
(-3540 3660);
DISPLAY 0.659574 (-3540 3660);
PAINT MONO (-3540 3660);
DISPLAY INVISIBLE (-3540 3660);
FORCEPROP 1 LASTPIN (-3550 3650) BN 2
J 0
(-3562 3658);
DISPLAY 0.489362 (-3562 3658);
PAINT GREEN (-3562 3658);
FORCEPROP 2 LAST CDS_LIB mstr_standard
J 0
(-3500 3650);
DISPLAY 0.723404 (-3500 3650);
PAINT MONO (-3500 3650);
DISPLAY INVISIBLE (-3500 3650);
FORCEPROP 1 LAST BODY_TYPE PLUMBING
J 0
(-3500 3700);
DISPLAY 0.872340 (-3500 3700);
PAINT GREEN (-3500 3700);
DISPLAY INVISIBLE (-3500 3700);
FORCEPROP 1 LAST HDL_TAP TRUE
J 0
(-3175 3525);
DISPLAY 0.872340 (-3175 3525);
DISPLAY INVISIBLE (-3175 3525);
FORCEPROP 1 LAST PATH I217
J 0
(-3502 3650);
DISPLAY 0.872340 (-3502 3650);
PAINT GREEN (-3502 3650);
DISPLAY INVISIBLE (-3502 3650);
FORCEADD TAP..1
(-3500 3550);
FORCEPROP 3 LASTPIN (-3550 3550) SIG_NAME M_H_CPU0_SA_DQS_DP<1>
J 0
(-3540 3560);
DISPLAY 0.659574 (-3540 3560);
PAINT MONO (-3540 3560);
DISPLAY INVISIBLE (-3540 3560);
FORCEPROP 1 LASTPIN (-3550 3550) BN 1
J 0
(-3562 3558);
DISPLAY 0.489362 (-3562 3558);
PAINT GREEN (-3562 3558);
FORCEPROP 2 LAST CDS_LIB mstr_standard
J 0
(-3500 3550);
DISPLAY 0.723404 (-3500 3550);
PAINT MONO (-3500 3550);
DISPLAY INVISIBLE (-3500 3550);
FORCEPROP 1 LAST BODY_TYPE PLUMBING
J 0
(-3500 3600);
DISPLAY 0.872340 (-3500 3600);
PAINT GREEN (-3500 3600);
DISPLAY INVISIBLE (-3500 3600);
FORCEPROP 1 LAST HDL_TAP TRUE
J 0
(-3175 3425);
DISPLAY 0.872340 (-3175 3425);
DISPLAY INVISIBLE (-3175 3425);
FORCEPROP 1 LAST PATH I218
J 0
(-3502 3550);
DISPLAY 0.872340 (-3502 3550);
PAINT GREEN (-3502 3550);
DISPLAY INVISIBLE (-3502 3550);
FORCEADD TAP..1
(-3500 3200);
FORCEPROP 3 LASTPIN (-3550 3200) SIG_NAME M_H_CPU0_SB_DQS_DP<8>
J 0
(-3540 3210);
DISPLAY 0.659574 (-3540 3210);
PAINT MONO (-3540 3210);
DISPLAY INVISIBLE (-3540 3210);
FORCEPROP 1 LASTPIN (-3550 3200) BN 8
J 0
(-3562 3208);
DISPLAY 0.489362 (-3562 3208);
PAINT GREEN (-3562 3208);
FORCEPROP 2 LAST CDS_LIB mstr_standard
J 0
(-3500 3200);
DISPLAY 0.723404 (-3500 3200);
PAINT MONO (-3500 3200);
DISPLAY INVISIBLE (-3500 3200);
FORCEPROP 1 LAST BODY_TYPE PLUMBING
J 0
(-3500 3250);
DISPLAY 0.872340 (-3500 3250);
PAINT GREEN (-3500 3250);
DISPLAY INVISIBLE (-3500 3250);
FORCEPROP 1 LAST HDL_TAP TRUE
J 0
(-3175 3075);
DISPLAY 0.872340 (-3175 3075);
DISPLAY INVISIBLE (-3175 3075);
FORCEPROP 1 LAST PATH I219
J 0
(-3502 3200);
DISPLAY 0.872340 (-3502 3200);
PAINT GREEN (-3502 3200);
DISPLAY INVISIBLE (-3502 3200);
FORCEADD SCONN288_DDR506112002KQ..1
(-6875 3600);
FORCEPROP 1 LAST LOCATION J69
J 0
(-7325 5675);
DISPLAY 0.468085 (-7325 5675);
PAINT SKYBLUE (-7325 5675);
FORCEPROP 0 LAST $SEC 1
J 0
(-7325 5825);
DISPLAY 0.680851 (-7325 5825);
PAINT MONO (-7325 5825);
DISPLAY INVISIBLE (-7325 5825);
FORCEPROP 2 LAST CDS_SEC 1
J 0
(-7325 5825);
DISPLAY 1.021277 (-7325 5825);
DISPLAY INVISIBLE (-7325 5825);
FORCEPROP 0 LASTPIN (-7475 3000) $PN 62
J 2
(-7485 3010);
DISPLAY 0.680851 (-7485 3010);
PAINT MONO (-7485 3010);
FORCEPROP 0 LASTPIN (-7475 5050) $PN 66
J 2
(-7485 5060);
DISPLAY 0.680851 (-7485 5060);
PAINT MONO (-7485 5060);
FORCEPROP 0 LASTPIN (-7475 4650) $PN 76
J 2
(-7485 4660);
DISPLAY 0.680851 (-7485 4660);
PAINT MONO (-7485 4660);
FORCEPROP 0 LASTPIN (-7475 5100) $PN 211
J 2
(-7485 5110);
DISPLAY 0.680851 (-7485 5110);
PAINT MONO (-7485 5110);
FORCEPROP 0 LASTPIN (-7475 4700) $PN 221
J 2
(-7485 4710);
DISPLAY 0.680851 (-7485 4710);
PAINT MONO (-7485 4710);
FORCEPROP 0 LASTPIN (-7475 5150) $PN 68
J 2
(-7485 5160);
DISPLAY 0.680851 (-7485 5160);
PAINT MONO (-7485 5160);
FORCEPROP 0 LASTPIN (-7475 4750) $PN 78
J 2
(-7485 4760);
DISPLAY 0.680851 (-7485 4760);
PAINT MONO (-7485 4760);
FORCEPROP 0 LASTPIN (-7475 5200) $PN 213
J 2
(-7485 5210);
DISPLAY 0.680851 (-7485 5210);
PAINT MONO (-7485 5210);
FORCEPROP 0 LASTPIN (-7475 4800) $PN 223
J 2
(-7485 4810);
DISPLAY 0.680851 (-7485 4810);
PAINT MONO (-7485 4810);
FORCEPROP 0 LASTPIN (-7475 5250) $PN 70
J 2
(-7485 5260);
DISPLAY 0.680851 (-7485 5260);
PAINT MONO (-7485 5260);
FORCEPROP 0 LASTPIN (-7475 4850) $PN 80
J 2
(-7485 4860);
DISPLAY 0.680851 (-7485 4860);
PAINT MONO (-7485 4860);
FORCEPROP 0 LASTPIN (-7475 5300) $PN 215
J 2
(-7485 5310);
DISPLAY 0.680851 (-7485 5310);
PAINT MONO (-7485 5310);
FORCEPROP 0 LASTPIN (-7475 4900) $PN 225
J 2
(-7485 4910);
DISPLAY 0.680851 (-7485 4910);
PAINT MONO (-7485 4910);
FORCEPROP 0 LASTPIN (-7475 5350) $PN 72
J 2
(-7485 5360);
DISPLAY 0.680851 (-7485 5360);
PAINT MONO (-7485 5360);
FORCEPROP 0 LASTPIN (-7475 4950) $PN 82
J 2
(-7485 4960);
DISPLAY 0.680851 (-7485 4960);
PAINT MONO (-7485 4960);
FORCEPROP 0 LASTPIN (-7475 3600) $PN 51
J 2
(-7485 3610);
DISPLAY 0.680851 (-7485 3610);
PAINT MONO (-7485 3610);
FORCEPROP 0 LASTPIN (-7475 3150) $PN 96
J 2
(-7485 3160);
DISPLAY 0.680851 (-7485 3160);
PAINT MONO (-7485 3160);
FORCEPROP 0 LASTPIN (-7475 3650) $PN 53
J 2
(-7485 3660);
DISPLAY 0.680851 (-7485 3660);
PAINT MONO (-7485 3660);
FORCEPROP 0 LASTPIN (-7475 3200) $PN 98
J 2
(-7485 3210);
DISPLAY 0.680851 (-7485 3210);
PAINT MONO (-7485 3210);
FORCEPROP 0 LASTPIN (-7475 3700) $PN 196
J 2
(-7485 3710);
DISPLAY 0.680851 (-7485 3710);
PAINT MONO (-7485 3710);
FORCEPROP 0 LASTPIN (-7475 3250) $PN 241
J 2
(-7485 3260);
DISPLAY 0.680851 (-7485 3260);
PAINT MONO (-7485 3260);
FORCEPROP 0 LASTPIN (-7475 3750) $PN 198
J 2
(-7485 3760);
DISPLAY 0.680851 (-7485 3760);
PAINT MONO (-7485 3760);
FORCEPROP 0 LASTPIN (-7475 3300) $PN 243
J 2
(-7485 3310);
DISPLAY 0.680851 (-7485 3310);
PAINT MONO (-7485 3310);
FORCEPROP 0 LASTPIN (-7475 3800) $PN 58
J 2
(-7485 3810);
DISPLAY 0.680851 (-7485 3810);
PAINT MONO (-7485 3810);
FORCEPROP 0 LASTPIN (-7475 3350) $PN 89
J 2
(-7485 3360);
DISPLAY 0.680851 (-7485 3360);
PAINT MONO (-7485 3360);
FORCEPROP 0 LASTPIN (-7475 3850) $PN 60
J 2
(-7485 3860);
DISPLAY 0.680851 (-7485 3860);
PAINT MONO (-7485 3860);
FORCEPROP 0 LASTPIN (-7475 3400) $PN 91
J 2
(-7485 3410);
DISPLAY 0.680851 (-7485 3410);
PAINT MONO (-7485 3410);
FORCEPROP 0 LASTPIN (-7475 3900) $PN 203
J 2
(-7485 3910);
DISPLAY 0.680851 (-7485 3910);
PAINT MONO (-7485 3910);
FORCEPROP 0 LASTPIN (-7475 3450) $PN 234
J 2
(-7485 3460);
DISPLAY 0.680851 (-7485 3460);
PAINT MONO (-7485 3460);
FORCEPROP 0 LASTPIN (-7475 3950) $PN 205
J 2
(-7485 3960);
DISPLAY 0.680851 (-7485 3960);
PAINT MONO (-7485 3960);
FORCEPROP 0 LASTPIN (-7475 3500) $PN 236
J 2
(-7485 3510);
DISPLAY 0.680851 (-7485 3510);
PAINT MONO (-7485 3510);
FORCEPROP 0 LASTPIN (-7475 4050) $PN 218
J 2
(-7485 4060);
DISPLAY 0.680851 (-7485 4060);
PAINT MONO (-7485 4060);
FORCEPROP 0 LASTPIN (-7475 4100) $PN 217
J 2
(-7485 4110);
DISPLAY 0.680851 (-7485 4110);
PAINT MONO (-7485 4110);
FORCEPROP 0 LASTPIN (-7475 4350) $PN 64
J 2
(-7485 4360);
DISPLAY 0.680851 (-7485 4360);
PAINT MONO (-7485 4360);
FORCEPROP 0 LASTPIN (-7475 4200) $PN 84
J 2
(-7485 4210);
DISPLAY 0.680851 (-7485 4210);
PAINT MONO (-7485 4210);
FORCEPROP 0 LASTPIN (-7475 4400) $PN 209
J 2
(-7485 4410);
DISPLAY 0.680851 (-7485 4410);
PAINT MONO (-7485 4410);
FORCEPROP 0 LASTPIN (-7475 4250) $PN 229
J 2
(-7485 4260);
DISPLAY 0.680851 (-7485 4260);
PAINT MONO (-7485 4260);
FORCEPROP 0 LASTPIN (-6275 3800) $PN 7
J 0
(-6265 3810);
DISPLAY 0.680851 (-6265 3810);
PAINT MONO (-6265 3810);
FORCEPROP 0 LASTPIN (-6275 2150) $PN 100
J 0
(-6265 2160);
DISPLAY 0.680851 (-6265 2160);
PAINT MONO (-6265 2160);
FORCEPROP 0 LASTPIN (-6275 3850) $PN 9
J 0
(-6265 3860);
DISPLAY 0.680851 (-6265 3860);
PAINT MONO (-6265 3860);
FORCEPROP 0 LASTPIN (-6275 2200) $PN 102
J 0
(-6265 2210);
DISPLAY 0.680851 (-6265 2210);
PAINT MONO (-6265 2210);
FORCEPROP 0 LASTPIN (-6275 3900) $PN 152
J 0
(-6265 3910);
DISPLAY 0.680851 (-6265 3910);
PAINT MONO (-6265 3910);
FORCEPROP 0 LASTPIN (-6275 2250) $PN 245
J 0
(-6265 2260);
DISPLAY 0.680851 (-6265 2260);
PAINT MONO (-6265 2260);
FORCEPROP 0 LASTPIN (-6275 3950) $PN 154
J 0
(-6265 3960);
DISPLAY 0.680851 (-6265 3960);
PAINT MONO (-6265 3960);
FORCEPROP 0 LASTPIN (-6275 2300) $PN 247
J 0
(-6265 2310);
DISPLAY 0.680851 (-6265 2310);
PAINT MONO (-6265 2310);
FORCEPROP 0 LASTPIN (-6275 4000) $PN 14
J 0
(-6265 4010);
DISPLAY 0.680851 (-6265 4010);
PAINT MONO (-6265 4010);
FORCEPROP 0 LASTPIN (-6275 2350) $PN 107
J 0
(-6265 2360);
DISPLAY 0.680851 (-6265 2360);
PAINT MONO (-6265 2360);
FORCEPROP 0 LASTPIN (-6275 4050) $PN 16
J 0
(-6265 4060);
DISPLAY 0.680851 (-6265 4060);
PAINT MONO (-6265 4060);
FORCEPROP 0 LASTPIN (-6275 2400) $PN 109
J 0
(-6265 2410);
DISPLAY 0.680851 (-6265 2410);
PAINT MONO (-6265 2410);
FORCEPROP 0 LASTPIN (-6275 4100) $PN 159
J 0
(-6265 4110);
DISPLAY 0.680851 (-6265 4110);
PAINT MONO (-6265 4110);
FORCEPROP 0 LASTPIN (-6275 2450) $PN 252
J 0
(-6265 2460);
DISPLAY 0.680851 (-6265 2460);
PAINT MONO (-6265 2460);
FORCEPROP 0 LASTPIN (-6275 4150) $PN 161
J 0
(-6265 4160);
DISPLAY 0.680851 (-6265 4160);
PAINT MONO (-6265 4160);
FORCEPROP 0 LASTPIN (-6275 2500) $PN 254
J 0
(-6265 2510);
DISPLAY 0.680851 (-6265 2510);
PAINT MONO (-6265 2510);
FORCEPROP 0 LASTPIN (-6275 4200) $PN 18
J 0
(-6265 4210);
DISPLAY 0.680851 (-6265 4210);
PAINT MONO (-6265 4210);
FORCEPROP 0 LASTPIN (-6275 2550) $PN 111
J 0
(-6265 2560);
DISPLAY 0.680851 (-6265 2560);
PAINT MONO (-6265 2560);
FORCEPROP 0 LASTPIN (-6275 4250) $PN 20
J 0
(-6265 4260);
DISPLAY 0.680851 (-6265 4260);
PAINT MONO (-6265 4260);
FORCEPROP 0 LASTPIN (-6275 2600) $PN 113
J 0
(-6265 2610);
DISPLAY 0.680851 (-6265 2610);
PAINT MONO (-6265 2610);
FORCEPROP 0 LASTPIN (-6275 4300) $PN 163
J 0
(-6265 4310);
DISPLAY 0.680851 (-6265 4310);
PAINT MONO (-6265 4310);
FORCEPROP 0 LASTPIN (-6275 2650) $PN 256
J 0
(-6265 2660);
DISPLAY 0.680851 (-6265 2660);
PAINT MONO (-6265 2660);
FORCEPROP 0 LASTPIN (-6275 4350) $PN 165
J 0
(-6265 4360);
DISPLAY 0.680851 (-6265 4360);
PAINT MONO (-6265 4360);
FORCEPROP 0 LASTPIN (-6275 2700) $PN 258
J 0
(-6265 2710);
DISPLAY 0.680851 (-6265 2710);
PAINT MONO (-6265 2710);
FORCEPROP 0 LASTPIN (-6275 4400) $PN 25
J 0
(-6265 4410);
DISPLAY 0.680851 (-6265 4410);
PAINT MONO (-6265 4410);
FORCEPROP 0 LASTPIN (-6275 2750) $PN 118
J 0
(-6265 2760);
DISPLAY 0.680851 (-6265 2760);
PAINT MONO (-6265 2760);
FORCEPROP 0 LASTPIN (-6275 4450) $PN 27
J 0
(-6265 4460);
DISPLAY 0.680851 (-6265 4460);
PAINT MONO (-6265 4460);
FORCEPROP 0 LASTPIN (-6275 2800) $PN 120
J 0
(-6265 2810);
DISPLAY 0.680851 (-6265 2810);
PAINT MONO (-6265 2810);
FORCEPROP 0 LASTPIN (-6275 4500) $PN 170
J 0
(-6265 4510);
DISPLAY 0.680851 (-6265 4510);
PAINT MONO (-6265 4510);
FORCEPROP 0 LASTPIN (-6275 2850) $PN 263
J 0
(-6265 2860);
DISPLAY 0.680851 (-6265 2860);
PAINT MONO (-6265 2860);
FORCEPROP 0 LASTPIN (-6275 4550) $PN 172
J 0
(-6265 4560);
DISPLAY 0.680851 (-6265 4560);
PAINT MONO (-6265 4560);
FORCEPROP 0 LASTPIN (-6275 2900) $PN 265
J 0
(-6265 2910);
DISPLAY 0.680851 (-6265 2910);
PAINT MONO (-6265 2910);
FORCEPROP 0 LASTPIN (-6275 4600) $PN 29
J 0
(-6265 4610);
DISPLAY 0.680851 (-6265 4610);
PAINT MONO (-6265 4610);
FORCEPROP 0 LASTPIN (-6275 2950) $PN 122
J 0
(-6265 2960);
DISPLAY 0.680851 (-6265 2960);
PAINT MONO (-6265 2960);
FORCEPROP 0 LASTPIN (-6275 4650) $PN 31
J 0
(-6265 4660);
DISPLAY 0.680851 (-6265 4660);
PAINT MONO (-6265 4660);
FORCEPROP 0 LASTPIN (-6275 3000) $PN 124
J 0
(-6265 3010);
DISPLAY 0.680851 (-6265 3010);
PAINT MONO (-6265 3010);
FORCEPROP 0 LASTPIN (-6275 4700) $PN 174
J 0
(-6265 4710);
DISPLAY 0.680851 (-6265 4710);
PAINT MONO (-6265 4710);
FORCEPROP 0 LASTPIN (-6275 3050) $PN 267
J 0
(-6265 3060);
DISPLAY 0.680851 (-6265 3060);
PAINT MONO (-6265 3060);
FORCEPROP 0 LASTPIN (-6275 4750) $PN 176
J 0
(-6265 4760);
DISPLAY 0.680851 (-6265 4760);
PAINT MONO (-6265 4760);
FORCEPROP 0 LASTPIN (-6275 3100) $PN 269
J 0
(-6265 3110);
DISPLAY 0.680851 (-6265 3110);
PAINT MONO (-6265 3110);
FORCEPROP 0 LASTPIN (-6275 4800) $PN 36
J 0
(-6265 4810);
DISPLAY 0.680851 (-6265 4810);
PAINT MONO (-6265 4810);
FORCEPROP 0 LASTPIN (-6275 3150) $PN 129
J 0
(-6265 3160);
DISPLAY 0.680851 (-6265 3160);
PAINT MONO (-6265 3160);
FORCEPROP 0 LASTPIN (-6275 4850) $PN 38
J 0
(-6265 4860);
DISPLAY 0.680851 (-6265 4860);
PAINT MONO (-6265 4860);
FORCEPROP 0 LASTPIN (-6275 3200) $PN 131
J 0
(-6265 3210);
DISPLAY 0.680851 (-6265 3210);
PAINT MONO (-6265 3210);
FORCEPROP 0 LASTPIN (-6275 4900) $PN 181
J 0
(-6265 4910);
DISPLAY 0.680851 (-6265 4910);
PAINT MONO (-6265 4910);
FORCEPROP 0 LASTPIN (-6275 3250) $PN 274
J 0
(-6265 3260);
DISPLAY 0.680851 (-6265 3260);
PAINT MONO (-6265 3260);
FORCEPROP 0 LASTPIN (-6275 4950) $PN 183
J 0
(-6265 4960);
DISPLAY 0.680851 (-6265 4960);
PAINT MONO (-6265 4960);
FORCEPROP 0 LASTPIN (-6275 3300) $PN 276
J 0
(-6265 3310);
DISPLAY 0.680851 (-6265 3310);
PAINT MONO (-6265 3310);
FORCEPROP 0 LASTPIN (-6275 5000) $PN 40
J 0
(-6265 5010);
DISPLAY 0.680851 (-6265 5010);
PAINT MONO (-6265 5010);
FORCEPROP 0 LASTPIN (-6275 3350) $PN 133
J 0
(-6265 3360);
DISPLAY 0.680851 (-6265 3360);
PAINT MONO (-6265 3360);
FORCEPROP 0 LASTPIN (-6275 5050) $PN 42
J 0
(-6265 5060);
DISPLAY 0.680851 (-6265 5060);
PAINT MONO (-6265 5060);
FORCEPROP 0 LASTPIN (-6275 3400) $PN 135
J 0
(-6265 3410);
DISPLAY 0.680851 (-6265 3410);
PAINT MONO (-6265 3410);
FORCEPROP 0 LASTPIN (-6275 5100) $PN 185
J 0
(-6265 5110);
DISPLAY 0.680851 (-6265 5110);
PAINT MONO (-6265 5110);
FORCEPROP 0 LASTPIN (-6275 3450) $PN 278
J 0
(-6265 3460);
DISPLAY 0.680851 (-6265 3460);
PAINT MONO (-6265 3460);
FORCEPROP 0 LASTPIN (-6275 5150) $PN 187
J 0
(-6265 5160);
DISPLAY 0.680851 (-6265 5160);
PAINT MONO (-6265 5160);
FORCEPROP 0 LASTPIN (-6275 3500) $PN 280
J 0
(-6265 3510);
DISPLAY 0.680851 (-6265 3510);
PAINT MONO (-6265 3510);
FORCEPROP 0 LASTPIN (-6275 5200) $PN 47
J 0
(-6265 5210);
DISPLAY 0.680851 (-6265 5210);
PAINT MONO (-6265 5210);
FORCEPROP 0 LASTPIN (-6275 3550) $PN 140
J 0
(-6265 3560);
DISPLAY 0.680851 (-6265 3560);
PAINT MONO (-6265 3560);
FORCEPROP 0 LASTPIN (-6275 5250) $PN 49
J 0
(-6265 5260);
DISPLAY 0.680851 (-6265 5260);
PAINT MONO (-6265 5260);
FORCEPROP 0 LASTPIN (-6275 3600) $PN 142
J 0
(-6265 3610);
DISPLAY 0.680851 (-6265 3610);
PAINT MONO (-6265 3610);
FORCEPROP 0 LASTPIN (-6275 5300) $PN 192
J 0
(-6265 5310);
DISPLAY 0.680851 (-6265 5310);
PAINT MONO (-6265 5310);
FORCEPROP 0 LASTPIN (-6275 3650) $PN 285
J 0
(-6265 3660);
DISPLAY 0.680851 (-6265 3660);
PAINT MONO (-6265 3660);
FORCEPROP 0 LASTPIN (-6275 5350) $PN 194
J 0
(-6265 5360);
DISPLAY 0.680851 (-6265 5360);
PAINT MONO (-6265 5360);
FORCEPROP 0 LASTPIN (-6275 3700) $PN 287
J 0
(-6265 3710);
DISPLAY 0.680851 (-6265 3710);
PAINT MONO (-6265 3710);
FORCEPROP 0 LASTPIN (-7475 2850) $PN 148
J 2
(-7485 2860);
DISPLAY 0.680851 (-7485 2860);
PAINT MONO (-7485 2860);
FORCEPROP 0 LASTPIN (-7475 2750) $PN 4
J 2
(-7485 2760);
DISPLAY 0.680851 (-7485 2760);
PAINT MONO (-7485 2760);
FORCEPROP 0 LASTPIN (-7475 2800) $PN 5
J 2
(-7485 2810);
DISPLAY 0.680851 (-7485 2810);
PAINT MONO (-7485 2810);
FORCEPROP 0 LASTPIN (-7475 1950) $PN 86
J 2
(-7485 1960);
DISPLAY 0.680851 (-7485 1960);
PAINT MONO (-7485 1960);
FORCEPROP 0 LASTPIN (-7475 1900) $PN 87
J 2
(-7485 1910);
DISPLAY 0.680851 (-7485 1910);
PAINT MONO (-7485 1910);
FORCEPROP 0 LASTPIN (-7475 4550) $PN 74
J 2
(-7485 4560);
DISPLAY 0.680851 (-7485 4560);
PAINT MONO (-7485 4560);
FORCEPROP 0 LASTPIN (-7475 4500) $PN 227
J 2
(-7485 4510);
DISPLAY 0.680851 (-7485 4510);
PAINT MONO (-7485 4510);
FORCEPROP 0 LASTPIN (-7475 2500) $PN 147
J 2
(-7485 2510);
DISPLAY 0.680851 (-7485 2510);
PAINT MONO (-7485 2510);
FORCEPROP 0 LASTPIN (-7475 3050) $PN 207
J 2
(-7485 3060);
DISPLAY 0.680851 (-7485 3060);
PAINT MONO (-7485 3060);
FORCEPROP 0 LASTPIN (-7475 2100) $PN 2
J 2
(-7485 2110);
DISPLAY 0.680851 (-7485 2110);
PAINT MONO (-7485 2110);
FORCEPROP 0 LASTPIN (-7475 2150) $PN 144
J 2
(-7485 2160);
DISPLAY 0.680851 (-7485 2160);
PAINT MONO (-7485 2160);
FORCEPROP 0 LASTPIN (-7475 2200) $PN 149
J 2
(-7485 2210);
DISPLAY 0.680851 (-7485 2210);
PAINT MONO (-7485 2210);
FORCEPROP 0 LASTPIN (-7475 2250) $PN 150
J 2
(-7485 2260);
DISPLAY 0.680851 (-7485 2260);
PAINT MONO (-7485 2260);
FORCEPROP 0 LASTPIN (-7475 2300) $PN 220
J 2
(-7485 2310);
DISPLAY 0.680851 (-7485 2310);
PAINT MONO (-7485 2310);
FORCEPROP 0 LASTPIN (-7475 2350) $PN 231
J 2
(-7485 2360);
DISPLAY 0.680851 (-7485 2360);
PAINT MONO (-7485 2360);
FORCEPROP 0 LASTPIN (-7475 2400) $PN 232
J 2
(-7485 2410);
DISPLAY 0.680851 (-7485 2410);
PAINT MONO (-7485 2410);
FORCEPROP 0 LASTPIN (-7475 2900) $PN 3
J 2
(-7485 2910);
DISPLAY 0.680851 (-7485 2910);
PAINT MONO (-7485 2910);
FORCEPROP 2 LAST PART_TYPE SMLF
J 0
(-7325 5775);
DISPLAY 1.021277 (-7325 5775);
FORCEPROP 1 LAST MATERIAL IO
J 0
(-7325 5525);
DISPLAY 0.468085 (-7325 5525);
PAINT SKYBLUE (-7325 5525);
FORCEPROP 2 LAST VALUE SCONN288_DDR506112002KQ
J 0
(-7325 5725);
DISPLAY 0.489362 (-7325 5725);
PAINT SKYBLUE (-7325 5725);
FORCEPROP 1 LAST PART_NUMBER DFHST8FS479
J 0
(-7325 5600);
DISPLAY 0.468085 (-7325 5600);
PAINT SKYBLUE (-7325 5600);
FORCEPROP 1 LAST CDS_LMAN_SYM_OUTLINE -450,1900,450,-1850
J 0
(-6875 3600);
DISPLAY 0.468085 (-6875 3600);
PAINT GREEN (-6875 3600);
DISPLAY INVISIBLE (-6875 3600);
FORCEPROP 1 LAST PATH I22
J 0
(-6875 3600);
DISPLAY 0.723404 (-6875 3600);
PAINT GREEN (-6875 3600);
DISPLAY INVISIBLE (-6875 3600);
FORCEPROP 1 LAST NEEDS_NO_SIZE TRUE
J 0
(-6875 3600);
DISPLAY 0.723404 (-6875 3600);
PAINT GREEN (-6875 3600);
DISPLAY INVISIBLE (-6875 3600);
FORCEPROP 2 LAST CDS_LIB pure_quanta
J 0
(-6875 3600);
DISPLAY INVISIBLE (-6875 3600);
FORCEADD TAP..1
(-3500 3300);
FORCEPROP 3 LASTPIN (-3550 3300) SIG_NAME M_H_CPU0_SB_DQS_DP<9>
J 0
(-3540 3310);
DISPLAY 0.659574 (-3540 3310);
PAINT MONO (-3540 3310);
DISPLAY INVISIBLE (-3540 3310);
FORCEPROP 1 LASTPIN (-3550 3300) BN 9
J 0
(-3562 3308);
DISPLAY 0.489362 (-3562 3308);
PAINT GREEN (-3562 3308);
FORCEPROP 2 LAST CDS_LIB mstr_standard
J 0
(-3500 3300);
DISPLAY 0.723404 (-3500 3300);
PAINT MONO (-3500 3300);
DISPLAY INVISIBLE (-3500 3300);
FORCEPROP 1 LAST BODY_TYPE PLUMBING
J 0
(-3500 3350);
DISPLAY 0.872340 (-3500 3350);
PAINT GREEN (-3500 3350);
DISPLAY INVISIBLE (-3500 3350);
FORCEPROP 1 LAST HDL_TAP TRUE
J 0
(-3175 3175);
DISPLAY 0.872340 (-3175 3175);
DISPLAY INVISIBLE (-3175 3175);
FORCEPROP 1 LAST PATH I220
J 0
(-3502 3300);
DISPLAY 0.872340 (-3502 3300);
PAINT GREEN (-3502 3300);
DISPLAY INVISIBLE (-3502 3300);
FORCEADD TAP..1
(-3300 3050);
FORCEPROP 3 LASTPIN (-3350 3050) SIG_NAME M_H_CPU0_SB_DQS_DN<7>
J 0
(-3340 3060);
DISPLAY 0.659574 (-3340 3060);
PAINT MONO (-3340 3060);
DISPLAY INVISIBLE (-3340 3060);
FORCEPROP 1 LASTPIN (-3350 3050) BN 7
J 0
(-3362 3058);
DISPLAY 0.489362 (-3362 3058);
PAINT GREEN (-3362 3058);
FORCEPROP 2 LAST CDS_LIB mstr_standard
J 0
(-3300 3050);
DISPLAY 0.723404 (-3300 3050);
PAINT MONO (-3300 3050);
DISPLAY INVISIBLE (-3300 3050);
FORCEPROP 1 LAST BODY_TYPE PLUMBING
J 0
(-3300 3100);
DISPLAY 0.872340 (-3300 3100);
PAINT GREEN (-3300 3100);
DISPLAY INVISIBLE (-3300 3100);
FORCEPROP 1 LAST HDL_TAP TRUE
J 0
(-2975 2925);
DISPLAY 0.872340 (-2975 2925);
DISPLAY INVISIBLE (-2975 2925);
FORCEPROP 1 LAST PATH I221
J 0
(-3302 3050);
DISPLAY 0.872340 (-3302 3050);
PAINT GREEN (-3302 3050);
DISPLAY INVISIBLE (-3302 3050);
FORCEADD TAP..1
(-3300 2950);
FORCEPROP 3 LASTPIN (-3350 2950) SIG_NAME M_H_CPU0_SB_DQS_DN<6>
J 0
(-3340 2960);
DISPLAY 0.659574 (-3340 2960);
PAINT MONO (-3340 2960);
DISPLAY INVISIBLE (-3340 2960);
FORCEPROP 1 LASTPIN (-3350 2950) BN 6
J 0
(-3362 2958);
DISPLAY 0.489362 (-3362 2958);
PAINT GREEN (-3362 2958);
FORCEPROP 2 LAST CDS_LIB mstr_standard
J 0
(-3300 2950);
DISPLAY 0.723404 (-3300 2950);
PAINT MONO (-3300 2950);
DISPLAY INVISIBLE (-3300 2950);
FORCEPROP 1 LAST BODY_TYPE PLUMBING
J 0
(-3300 3000);
DISPLAY 0.872340 (-3300 3000);
PAINT GREEN (-3300 3000);
DISPLAY INVISIBLE (-3300 3000);
FORCEPROP 1 LAST HDL_TAP TRUE
J 0
(-2975 2825);
DISPLAY 0.872340 (-2975 2825);
DISPLAY INVISIBLE (-2975 2825);
FORCEPROP 1 LAST PATH I222
J 0
(-3302 2950);
DISPLAY 0.872340 (-3302 2950);
PAINT GREEN (-3302 2950);
DISPLAY INVISIBLE (-3302 2950);
FORCEADD TAP..1
(-3300 2850);
FORCEPROP 3 LASTPIN (-3350 2850) SIG_NAME M_H_CPU0_SB_DQS_DN<5>
J 0
(-3340 2860);
DISPLAY 0.659574 (-3340 2860);
PAINT MONO (-3340 2860);
DISPLAY INVISIBLE (-3340 2860);
FORCEPROP 1 LASTPIN (-3350 2850) BN 5
J 0
(-3362 2858);
DISPLAY 0.489362 (-3362 2858);
PAINT GREEN (-3362 2858);
FORCEPROP 2 LAST CDS_LIB mstr_standard
J 0
(-3300 2850);
DISPLAY 0.723404 (-3300 2850);
PAINT MONO (-3300 2850);
DISPLAY INVISIBLE (-3300 2850);
FORCEPROP 1 LAST BODY_TYPE PLUMBING
J 0
(-3300 2900);
DISPLAY 0.872340 (-3300 2900);
PAINT GREEN (-3300 2900);
DISPLAY INVISIBLE (-3300 2900);
FORCEPROP 1 LAST HDL_TAP TRUE
J 0
(-2975 2725);
DISPLAY 0.872340 (-2975 2725);
DISPLAY INVISIBLE (-2975 2725);
FORCEPROP 1 LAST PATH I223
J 0
(-3302 2850);
DISPLAY 0.872340 (-3302 2850);
PAINT GREEN (-3302 2850);
DISPLAY INVISIBLE (-3302 2850);
FORCEADD TAP..1
(-3300 2650);
FORCEPROP 3 LASTPIN (-3350 2650) SIG_NAME M_H_CPU0_SB_DQS_DN<3>
J 0
(-3340 2660);
DISPLAY 0.659574 (-3340 2660);
PAINT MONO (-3340 2660);
DISPLAY INVISIBLE (-3340 2660);
FORCEPROP 1 LASTPIN (-3350 2650) BN 3
J 0
(-3362 2658);
DISPLAY 0.489362 (-3362 2658);
PAINT GREEN (-3362 2658);
FORCEPROP 2 LAST CDS_LIB mstr_standard
J 0
(-3300 2650);
DISPLAY 0.723404 (-3300 2650);
PAINT MONO (-3300 2650);
DISPLAY INVISIBLE (-3300 2650);
FORCEPROP 1 LAST BODY_TYPE PLUMBING
J 0
(-3300 2700);
DISPLAY 0.872340 (-3300 2700);
PAINT GREEN (-3300 2700);
DISPLAY INVISIBLE (-3300 2700);
FORCEPROP 1 LAST HDL_TAP TRUE
J 0
(-2975 2525);
DISPLAY 0.872340 (-2975 2525);
DISPLAY INVISIBLE (-2975 2525);
FORCEPROP 1 LAST PATH I224
J 0
(-3302 2650);
DISPLAY 0.872340 (-3302 2650);
PAINT GREEN (-3302 2650);
DISPLAY INVISIBLE (-3302 2650);
FORCEADD TAP..1
(-3300 2750);
FORCEPROP 3 LASTPIN (-3350 2750) SIG_NAME M_H_CPU0_SB_DQS_DN<4>
J 0
(-3340 2760);
DISPLAY 0.659574 (-3340 2760);
PAINT MONO (-3340 2760);
DISPLAY INVISIBLE (-3340 2760);
FORCEPROP 1 LASTPIN (-3350 2750) BN 4
J 0
(-3362 2758);
DISPLAY 0.489362 (-3362 2758);
PAINT GREEN (-3362 2758);
FORCEPROP 2 LAST CDS_LIB mstr_standard
J 0
(-3300 2750);
DISPLAY 0.723404 (-3300 2750);
PAINT MONO (-3300 2750);
DISPLAY INVISIBLE (-3300 2750);
FORCEPROP 1 LAST BODY_TYPE PLUMBING
J 0
(-3300 2800);
DISPLAY 0.872340 (-3300 2800);
PAINT GREEN (-3300 2800);
DISPLAY INVISIBLE (-3300 2800);
FORCEPROP 1 LAST HDL_TAP TRUE
J 0
(-2975 2625);
DISPLAY 0.872340 (-2975 2625);
DISPLAY INVISIBLE (-2975 2625);
FORCEPROP 1 LAST PATH I225
J 0
(-3302 2750);
DISPLAY 0.872340 (-3302 2750);
PAINT GREEN (-3302 2750);
DISPLAY INVISIBLE (-3302 2750);
FORCEADD TAP..1
(-3500 2900);
FORCEPROP 3 LASTPIN (-3550 2900) SIG_NAME M_H_CPU0_SB_DQS_DP<5>
J 0
(-3540 2910);
DISPLAY 0.659574 (-3540 2910);
PAINT MONO (-3540 2910);
DISPLAY INVISIBLE (-3540 2910);
FORCEPROP 1 LASTPIN (-3550 2900) BN 5
J 0
(-3562 2908);
DISPLAY 0.489362 (-3562 2908);
PAINT GREEN (-3562 2908);
FORCEPROP 2 LAST CDS_LIB mstr_standard
J 0
(-3500 2900);
DISPLAY 0.723404 (-3500 2900);
PAINT MONO (-3500 2900);
DISPLAY INVISIBLE (-3500 2900);
FORCEPROP 1 LAST BODY_TYPE PLUMBING
J 0
(-3500 2950);
DISPLAY 0.872340 (-3500 2950);
PAINT GREEN (-3500 2950);
DISPLAY INVISIBLE (-3500 2950);
FORCEPROP 1 LAST HDL_TAP TRUE
J 0
(-3175 2775);
DISPLAY 0.872340 (-3175 2775);
DISPLAY INVISIBLE (-3175 2775);
FORCEPROP 1 LAST PATH I226
J 0
(-3502 2900);
DISPLAY 0.872340 (-3502 2900);
PAINT GREEN (-3502 2900);
DISPLAY INVISIBLE (-3502 2900);
FORCEADD TAP..1
(-3500 3100);
FORCEPROP 3 LASTPIN (-3550 3100) SIG_NAME M_H_CPU0_SB_DQS_DP<7>
J 0
(-3540 3110);
DISPLAY 0.659574 (-3540 3110);
PAINT MONO (-3540 3110);
DISPLAY INVISIBLE (-3540 3110);
FORCEPROP 1 LASTPIN (-3550 3100) BN 7
J 0
(-3562 3108);
DISPLAY 0.489362 (-3562 3108);
PAINT GREEN (-3562 3108);
FORCEPROP 2 LAST CDS_LIB mstr_standard
J 0
(-3500 3100);
DISPLAY 0.723404 (-3500 3100);
PAINT MONO (-3500 3100);
DISPLAY INVISIBLE (-3500 3100);
FORCEPROP 1 LAST BODY_TYPE PLUMBING
J 0
(-3500 3150);
DISPLAY 0.872340 (-3500 3150);
PAINT GREEN (-3500 3150);
DISPLAY INVISIBLE (-3500 3150);
FORCEPROP 1 LAST HDL_TAP TRUE
J 0
(-3175 2975);
DISPLAY 0.872340 (-3175 2975);
DISPLAY INVISIBLE (-3175 2975);
FORCEPROP 1 LAST PATH I227
J 0
(-3502 3100);
DISPLAY 0.872340 (-3502 3100);
PAINT GREEN (-3502 3100);
DISPLAY INVISIBLE (-3502 3100);
FORCEADD TAP..1
(-3500 3000);
FORCEPROP 3 LASTPIN (-3550 3000) SIG_NAME M_H_CPU0_SB_DQS_DP<6>
J 0
(-3540 3010);
DISPLAY 0.659574 (-3540 3010);
PAINT MONO (-3540 3010);
DISPLAY INVISIBLE (-3540 3010);
FORCEPROP 1 LASTPIN (-3550 3000) BN 6
J 0
(-3562 3008);
DISPLAY 0.489362 (-3562 3008);
PAINT GREEN (-3562 3008);
FORCEPROP 2 LAST CDS_LIB mstr_standard
J 0
(-3500 3000);
DISPLAY 0.723404 (-3500 3000);
PAINT MONO (-3500 3000);
DISPLAY INVISIBLE (-3500 3000);
FORCEPROP 1 LAST BODY_TYPE PLUMBING
J 0
(-3500 3050);
DISPLAY 0.872340 (-3500 3050);
PAINT GREEN (-3500 3050);
DISPLAY INVISIBLE (-3500 3050);
FORCEPROP 1 LAST HDL_TAP TRUE
J 0
(-3175 2875);
DISPLAY 0.872340 (-3175 2875);
DISPLAY INVISIBLE (-3175 2875);
FORCEPROP 1 LAST PATH I228
J 0
(-3502 3000);
DISPLAY 0.872340 (-3502 3000);
PAINT GREEN (-3502 3000);
DISPLAY INVISIBLE (-3502 3000);
FORCEADD TAP..1
(-3500 2800);
FORCEPROP 3 LASTPIN (-3550 2800) SIG_NAME M_H_CPU0_SB_DQS_DP<4>
J 0
(-3540 2810);
DISPLAY 0.659574 (-3540 2810);
PAINT MONO (-3540 2810);
DISPLAY INVISIBLE (-3540 2810);
FORCEPROP 1 LASTPIN (-3550 2800) BN 4
J 0
(-3562 2808);
DISPLAY 0.489362 (-3562 2808);
PAINT GREEN (-3562 2808);
FORCEPROP 2 LAST CDS_LIB mstr_standard
J 0
(-3500 2800);
DISPLAY 0.723404 (-3500 2800);
PAINT MONO (-3500 2800);
DISPLAY INVISIBLE (-3500 2800);
FORCEPROP 1 LAST BODY_TYPE PLUMBING
J 0
(-3500 2850);
DISPLAY 0.872340 (-3500 2850);
PAINT GREEN (-3500 2850);
DISPLAY INVISIBLE (-3500 2850);
FORCEPROP 1 LAST HDL_TAP TRUE
J 0
(-3175 2675);
DISPLAY 0.872340 (-3175 2675);
DISPLAY INVISIBLE (-3175 2675);
FORCEPROP 1 LAST PATH I229
J 0
(-3502 2800);
DISPLAY 0.872340 (-3502 2800);
PAINT GREEN (-3502 2800);
DISPLAY INVISIBLE (-3502 2800);
FORCEADD TAP..1
R 2
(-7725 3150);
FORCEPROP 3 LASTPIN (-7675 3150) SIG_NAME M_H_CPU0_SB_CB<0>
J 0
(-7665 3160);
DISPLAY 0.659574 (-7665 3160);
PAINT MONO (-7665 3160);
DISPLAY INVISIBLE (-7665 3160);
FORCEPROP 1 LASTPIN (-7675 3150) BN 0
J 2
(-7663 3158);
DISPLAY 0.489362 (-7663 3158);
PAINT GREEN (-7663 3158);
FORCEPROP 2 LAST CDS_LIB mstr_standard
J 0
(-7725 3150);
DISPLAY 0.723404 (-7725 3150);
PAINT MONO (-7725 3150);
DISPLAY INVISIBLE (-7725 3150);
FORCEPROP 1 LAST BODY_TYPE PLUMBING
J 2
(-7725 3200);
DISPLAY 0.872340 (-7725 3200);
PAINT GREEN (-7725 3200);
DISPLAY INVISIBLE (-7725 3200);
FORCEPROP 1 LAST HDL_TAP TRUE
J 2
(-8050 3025);
DISPLAY 0.872340 (-8050 3025);
DISPLAY INVISIBLE (-8050 3025);
FORCEPROP 1 LAST PATH I23
J 2
(-7723 3150);
DISPLAY 0.872340 (-7723 3150);
PAINT GREEN (-7723 3150);
DISPLAY INVISIBLE (-7723 3150);
FORCEADD TAP..1
(-3500 2700);
FORCEPROP 3 LASTPIN (-3550 2700) SIG_NAME M_H_CPU0_SB_DQS_DP<3>
J 0
(-3540 2710);
DISPLAY 0.659574 (-3540 2710);
PAINT MONO (-3540 2710);
DISPLAY INVISIBLE (-3540 2710);
FORCEPROP 1 LASTPIN (-3550 2700) BN 3
J 0
(-3562 2708);
DISPLAY 0.489362 (-3562 2708);
PAINT GREEN (-3562 2708);
FORCEPROP 2 LAST CDS_LIB mstr_standard
J 0
(-3500 2700);
DISPLAY 0.723404 (-3500 2700);
PAINT MONO (-3500 2700);
DISPLAY INVISIBLE (-3500 2700);
FORCEPROP 1 LAST BODY_TYPE PLUMBING
J 0
(-3500 2750);
DISPLAY 0.872340 (-3500 2750);
PAINT GREEN (-3500 2750);
DISPLAY INVISIBLE (-3500 2750);
FORCEPROP 1 LAST HDL_TAP TRUE
J 0
(-3175 2575);
DISPLAY 0.872340 (-3175 2575);
DISPLAY INVISIBLE (-3175 2575);
FORCEPROP 1 LAST PATH I230
J 0
(-3502 2700);
DISPLAY 0.872340 (-3502 2700);
PAINT GREEN (-3502 2700);
DISPLAY INVISIBLE (-3502 2700);
FORCEADD TAP..1
(-3300 2550);
FORCEPROP 3 LASTPIN (-3350 2550) SIG_NAME M_H_CPU0_SB_DQS_DN<2>
J 0
(-3340 2560);
DISPLAY 0.659574 (-3340 2560);
PAINT MONO (-3340 2560);
DISPLAY INVISIBLE (-3340 2560);
FORCEPROP 1 LASTPIN (-3350 2550) BN 2
J 0
(-3362 2558);
DISPLAY 0.489362 (-3362 2558);
PAINT GREEN (-3362 2558);
FORCEPROP 2 LAST CDS_LIB mstr_standard
J 0
(-3300 2550);
DISPLAY 0.723404 (-3300 2550);
PAINT MONO (-3300 2550);
DISPLAY INVISIBLE (-3300 2550);
FORCEPROP 1 LAST BODY_TYPE PLUMBING
J 0
(-3300 2600);
DISPLAY 0.872340 (-3300 2600);
PAINT GREEN (-3300 2600);
DISPLAY INVISIBLE (-3300 2600);
FORCEPROP 1 LAST HDL_TAP TRUE
J 0
(-2975 2425);
DISPLAY 0.872340 (-2975 2425);
DISPLAY INVISIBLE (-2975 2425);
FORCEPROP 1 LAST PATH I231
J 0
(-3302 2550);
DISPLAY 0.872340 (-3302 2550);
PAINT GREEN (-3302 2550);
DISPLAY INVISIBLE (-3302 2550);
FORCEADD TAP..1
(-3300 2450);
FORCEPROP 3 LASTPIN (-3350 2450) SIG_NAME M_H_CPU0_SB_DQS_DN<1>
J 0
(-3340 2460);
DISPLAY 0.659574 (-3340 2460);
PAINT MONO (-3340 2460);
DISPLAY INVISIBLE (-3340 2460);
FORCEPROP 1 LASTPIN (-3350 2450) BN 1
J 0
(-3362 2458);
DISPLAY 0.489362 (-3362 2458);
PAINT GREEN (-3362 2458);
FORCEPROP 2 LAST CDS_LIB mstr_standard
J 0
(-3300 2450);
DISPLAY 0.723404 (-3300 2450);
PAINT MONO (-3300 2450);
DISPLAY INVISIBLE (-3300 2450);
FORCEPROP 1 LAST BODY_TYPE PLUMBING
J 0
(-3300 2500);
DISPLAY 0.872340 (-3300 2500);
PAINT GREEN (-3300 2500);
DISPLAY INVISIBLE (-3300 2500);
FORCEPROP 1 LAST HDL_TAP TRUE
J 0
(-2975 2325);
DISPLAY 0.872340 (-2975 2325);
DISPLAY INVISIBLE (-2975 2325);
FORCEPROP 1 LAST PATH I232
J 0
(-3302 2450);
DISPLAY 0.872340 (-3302 2450);
PAINT GREEN (-3302 2450);
DISPLAY INVISIBLE (-3302 2450);
FORCEADD TAP..1
(-3300 2350);
FORCEPROP 3 LASTPIN (-3350 2350) SIG_NAME M_H_CPU0_SB_DQS_DN<0>
J 0
(-3340 2360);
DISPLAY 0.659574 (-3340 2360);
PAINT MONO (-3340 2360);
DISPLAY INVISIBLE (-3340 2360);
FORCEPROP 1 LASTPIN (-3350 2350) BN 0
J 0
(-3362 2358);
DISPLAY 0.489362 (-3362 2358);
PAINT GREEN (-3362 2358);
FORCEPROP 2 LAST CDS_LIB mstr_standard
J 0
(-3300 2350);
DISPLAY 0.723404 (-3300 2350);
PAINT MONO (-3300 2350);
DISPLAY INVISIBLE (-3300 2350);
FORCEPROP 1 LAST BODY_TYPE PLUMBING
J 0
(-3300 2400);
DISPLAY 0.872340 (-3300 2400);
PAINT GREEN (-3300 2400);
DISPLAY INVISIBLE (-3300 2400);
FORCEPROP 1 LAST HDL_TAP TRUE
J 0
(-2975 2225);
DISPLAY 0.872340 (-2975 2225);
DISPLAY INVISIBLE (-2975 2225);
FORCEPROP 1 LAST PATH I233
J 0
(-3302 2350);
DISPLAY 0.872340 (-3302 2350);
PAINT GREEN (-3302 2350);
DISPLAY INVISIBLE (-3302 2350);
FORCEADD TAP..1
(-3500 2400);
FORCEPROP 3 LASTPIN (-3550 2400) SIG_NAME M_H_CPU0_SB_DQS_DP<0>
J 0
(-3540 2410);
DISPLAY 0.659574 (-3540 2410);
PAINT MONO (-3540 2410);
DISPLAY INVISIBLE (-3540 2410);
FORCEPROP 1 LASTPIN (-3550 2400) BN 0
J 0
(-3562 2408);
DISPLAY 0.489362 (-3562 2408);
PAINT GREEN (-3562 2408);
FORCEPROP 2 LAST CDS_LIB mstr_standard
J 0
(-3500 2400);
DISPLAY 0.723404 (-3500 2400);
PAINT MONO (-3500 2400);
DISPLAY INVISIBLE (-3500 2400);
FORCEPROP 1 LAST BODY_TYPE PLUMBING
J 0
(-3500 2450);
DISPLAY 0.872340 (-3500 2450);
PAINT GREEN (-3500 2450);
DISPLAY INVISIBLE (-3500 2450);
FORCEPROP 1 LAST HDL_TAP TRUE
J 0
(-3175 2275);
DISPLAY 0.872340 (-3175 2275);
DISPLAY INVISIBLE (-3175 2275);
FORCEPROP 1 LAST PATH I234
J 0
(-3502 2400);
DISPLAY 0.872340 (-3502 2400);
PAINT GREEN (-3502 2400);
DISPLAY INVISIBLE (-3502 2400);
FORCEADD TAP..1
(-3500 2500);
FORCEPROP 3 LASTPIN (-3550 2500) SIG_NAME M_H_CPU0_SB_DQS_DP<1>
J 0
(-3540 2510);
DISPLAY 0.659574 (-3540 2510);
PAINT MONO (-3540 2510);
DISPLAY INVISIBLE (-3540 2510);
FORCEPROP 1 LASTPIN (-3550 2500) BN 1
J 0
(-3562 2508);
DISPLAY 0.489362 (-3562 2508);
PAINT GREEN (-3562 2508);
FORCEPROP 2 LAST CDS_LIB mstr_standard
J 0
(-3500 2500);
DISPLAY 0.723404 (-3500 2500);
PAINT MONO (-3500 2500);
DISPLAY INVISIBLE (-3500 2500);
FORCEPROP 1 LAST BODY_TYPE PLUMBING
J 0
(-3500 2550);
DISPLAY 0.872340 (-3500 2550);
PAINT GREEN (-3500 2550);
DISPLAY INVISIBLE (-3500 2550);
FORCEPROP 1 LAST HDL_TAP TRUE
J 0
(-3175 2375);
DISPLAY 0.872340 (-3175 2375);
DISPLAY INVISIBLE (-3175 2375);
FORCEPROP 1 LAST PATH I235
J 0
(-3502 2500);
DISPLAY 0.872340 (-3502 2500);
PAINT GREEN (-3502 2500);
DISPLAY INVISIBLE (-3502 2500);
FORCEADD TAP..1
(-3500 2600);
FORCEPROP 3 LASTPIN (-3550 2600) SIG_NAME M_H_CPU0_SB_DQS_DP<2>
J 0
(-3540 2610);
DISPLAY 0.659574 (-3540 2610);
PAINT MONO (-3540 2610);
DISPLAY INVISIBLE (-3540 2610);
FORCEPROP 1 LASTPIN (-3550 2600) BN 2
J 0
(-3562 2608);
DISPLAY 0.489362 (-3562 2608);
PAINT GREEN (-3562 2608);
FORCEPROP 2 LAST CDS_LIB mstr_standard
J 0
(-3500 2600);
DISPLAY 0.723404 (-3500 2600);
PAINT MONO (-3500 2600);
DISPLAY INVISIBLE (-3500 2600);
FORCEPROP 1 LAST BODY_TYPE PLUMBING
J 0
(-3500 2650);
DISPLAY 0.872340 (-3500 2650);
PAINT GREEN (-3500 2650);
DISPLAY INVISIBLE (-3500 2650);
FORCEPROP 1 LAST HDL_TAP TRUE
J 0
(-3175 2475);
DISPLAY 0.872340 (-3175 2475);
DISPLAY INVISIBLE (-3175 2475);
FORCEPROP 1 LAST PATH I236
J 0
(-3502 2600);
DISPLAY 0.872340 (-3502 2600);
PAINT GREEN (-3502 2600);
DISPLAY INVISIBLE (-3502 2600);
FORCEADD SCONN288_DDR506112002KQ..2
(-4450 3350);
FORCEPROP 1 LAST LOCATION J69
J 0
(-5050 4675);
DISPLAY 0.468085 (-5050 4675);
PAINT SKYBLUE (-5050 4675);
FORCEPROP 0 LAST $SEC 2
J 0
(-4900 4825);
DISPLAY 0.680851 (-4900 4825);
PAINT MONO (-4900 4825);
DISPLAY INVISIBLE (-4900 4825);
FORCEPROP 0 LAST CDS_SEC 2
J 0
(-4900 4825);
DISPLAY 1.021277 (-4900 4825);
DISPLAY INVISIBLE (-4900 4825);
FORCEPROP 0 LASTPIN (-3700 3400) $PN 12
J 0
(-3690 3410);
DISPLAY 0.680851 (-3690 3410);
PAINT MONO (-3690 3410);
FORCEPROP 0 LASTPIN (-3700 3450) $PN 11
J 0
(-3690 3460);
DISPLAY 0.680851 (-3690 3460);
PAINT MONO (-3690 3460);
FORCEPROP 0 LASTPIN (-3700 2350) $PN 105
J 0
(-3690 2360);
DISPLAY 0.680851 (-3690 2360);
PAINT MONO (-3690 2360);
FORCEPROP 0 LASTPIN (-3700 2400) $PN 104
J 0
(-3690 2410);
DISPLAY 0.680851 (-3690 2410);
PAINT MONO (-3690 2410);
FORCEPROP 0 LASTPIN (-3700 3500) $PN 23
J 0
(-3690 3510);
DISPLAY 0.680851 (-3690 3510);
PAINT MONO (-3690 3510);
FORCEPROP 0 LASTPIN (-3700 3550) $PN 22
J 0
(-3690 3560);
DISPLAY 0.680851 (-3690 3560);
PAINT MONO (-3690 3560);
FORCEPROP 0 LASTPIN (-3700 2450) $PN 116
J 0
(-3690 2460);
DISPLAY 0.680851 (-3690 2460);
PAINT MONO (-3690 2460);
FORCEPROP 0 LASTPIN (-3700 2500) $PN 115
J 0
(-3690 2510);
DISPLAY 0.680851 (-3690 2510);
PAINT MONO (-3690 2510);
FORCEPROP 0 LASTPIN (-3700 3600) $PN 34
J 0
(-3690 3610);
DISPLAY 0.680851 (-3690 3610);
PAINT MONO (-3690 3610);
FORCEPROP 0 LASTPIN (-3700 3650) $PN 33
J 0
(-3690 3660);
DISPLAY 0.680851 (-3690 3660);
PAINT MONO (-3690 3660);
FORCEPROP 0 LASTPIN (-3700 2550) $PN 127
J 0
(-3690 2560);
DISPLAY 0.680851 (-3690 2560);
PAINT MONO (-3690 2560);
FORCEPROP 0 LASTPIN (-3700 2600) $PN 126
J 0
(-3690 2610);
DISPLAY 0.680851 (-3690 2610);
PAINT MONO (-3690 2610);
FORCEPROP 0 LASTPIN (-3700 3700) $PN 45
J 0
(-3690 3710);
DISPLAY 0.680851 (-3690 3710);
PAINT MONO (-3690 3710);
FORCEPROP 0 LASTPIN (-3700 3750) $PN 44
J 0
(-3690 3760);
DISPLAY 0.680851 (-3690 3760);
PAINT MONO (-3690 3760);
FORCEPROP 0 LASTPIN (-3700 2650) $PN 138
J 0
(-3690 2660);
DISPLAY 0.680851 (-3690 2660);
PAINT MONO (-3690 2660);
FORCEPROP 0 LASTPIN (-3700 2700) $PN 137
J 0
(-3690 2710);
DISPLAY 0.680851 (-3690 2710);
PAINT MONO (-3690 2710);
FORCEPROP 0 LASTPIN (-3700 3800) $PN 56
J 0
(-3690 3810);
DISPLAY 0.680851 (-3690 3810);
PAINT MONO (-3690 3810);
FORCEPROP 0 LASTPIN (-3700 3850) $PN 55
J 0
(-3690 3860);
DISPLAY 0.680851 (-3690 3860);
PAINT MONO (-3690 3860);
FORCEPROP 0 LASTPIN (-3700 2750) $PN 238
J 0
(-3690 2760);
DISPLAY 0.680851 (-3690 2760);
PAINT MONO (-3690 2760);
FORCEPROP 0 LASTPIN (-3700 2800) $PN 239
J 0
(-3690 2810);
DISPLAY 0.680851 (-3690 2810);
PAINT MONO (-3690 2810);
FORCEPROP 0 LASTPIN (-3700 3900) $PN 156
J 0
(-3690 3910);
DISPLAY 0.680851 (-3690 3910);
PAINT MONO (-3690 3910);
FORCEPROP 0 LASTPIN (-3700 3950) $PN 157
J 0
(-3690 3960);
DISPLAY 0.680851 (-3690 3960);
PAINT MONO (-3690 3960);
FORCEPROP 0 LASTPIN (-3700 2850) $PN 249
J 0
(-3690 2860);
DISPLAY 0.680851 (-3690 2860);
PAINT MONO (-3690 2860);
FORCEPROP 0 LASTPIN (-3700 2900) $PN 250
J 0
(-3690 2910);
DISPLAY 0.680851 (-3690 2910);
PAINT MONO (-3690 2910);
FORCEPROP 0 LASTPIN (-3700 4000) $PN 167
J 0
(-3690 4010);
DISPLAY 0.680851 (-3690 4010);
PAINT MONO (-3690 4010);
FORCEPROP 0 LASTPIN (-3700 4050) $PN 168
J 0
(-3690 4060);
DISPLAY 0.680851 (-3690 4060);
PAINT MONO (-3690 4060);
FORCEPROP 0 LASTPIN (-3700 2950) $PN 260
J 0
(-3690 2960);
DISPLAY 0.680851 (-3690 2960);
PAINT MONO (-3690 2960);
FORCEPROP 0 LASTPIN (-3700 3000) $PN 261
J 0
(-3690 3010);
DISPLAY 0.680851 (-3690 3010);
PAINT MONO (-3690 3010);
FORCEPROP 0 LASTPIN (-3700 4100) $PN 178
J 0
(-3690 4110);
DISPLAY 0.680851 (-3690 4110);
PAINT MONO (-3690 4110);
FORCEPROP 0 LASTPIN (-3700 4150) $PN 179
J 0
(-3690 4160);
DISPLAY 0.680851 (-3690 4160);
PAINT MONO (-3690 4160);
FORCEPROP 0 LASTPIN (-3700 3050) $PN 271
J 0
(-3690 3060);
DISPLAY 0.680851 (-3690 3060);
PAINT MONO (-3690 3060);
FORCEPROP 0 LASTPIN (-3700 3100) $PN 272
J 0
(-3690 3110);
DISPLAY 0.680851 (-3690 3110);
PAINT MONO (-3690 3110);
FORCEPROP 0 LASTPIN (-3700 4200) $PN 189
J 0
(-3690 4210);
DISPLAY 0.680851 (-3690 4210);
PAINT MONO (-3690 4210);
FORCEPROP 0 LASTPIN (-3700 4250) $PN 190
J 0
(-3690 4260);
DISPLAY 0.680851 (-3690 4260);
PAINT MONO (-3690 4260);
FORCEPROP 0 LASTPIN (-3700 3150) $PN 282
J 0
(-3690 3160);
DISPLAY 0.680851 (-3690 3160);
PAINT MONO (-3690 3160);
FORCEPROP 0 LASTPIN (-3700 3200) $PN 283
J 0
(-3690 3210);
DISPLAY 0.680851 (-3690 3210);
PAINT MONO (-3690 3210);
FORCEPROP 0 LASTPIN (-3700 4300) $PN 200
J 0
(-3690 4310);
DISPLAY 0.680851 (-3690 4310);
PAINT MONO (-3690 4310);
FORCEPROP 0 LASTPIN (-3700 4350) $PN 201
J 0
(-3690 4360);
DISPLAY 0.680851 (-3690 4360);
PAINT MONO (-3690 4360);
FORCEPROP 0 LASTPIN (-3700 3250) $PN 94
J 0
(-3690 3260);
DISPLAY 0.680851 (-3690 3260);
PAINT MONO (-3690 3260);
FORCEPROP 0 LASTPIN (-3700 3300) $PN 93
J 0
(-3690 3310);
DISPLAY 0.680851 (-3690 3310);
PAINT MONO (-3690 3310);
FORCEPROP 2 LAST VALUE SCONN288_DDR506112002KQ
J 0
(-4900 4725);
DISPLAY 0.489362 (-4900 4725);
PAINT SKYBLUE (-4900 4725);
FORCEPROP 2 LAST PART_TYPE SMLF
J 0
(-4900 4775);
DISPLAY 1.021277 (-4900 4775);
FORCEPROP 1 LAST PART_NUMBER DFHST8FS479
J 0
(-5050 4600);
DISPLAY 0.468085 (-5050 4600);
PAINT SKYBLUE (-5050 4600);
FORCEPROP 1 LAST MATERIAL IO
J 0
(-5050 4525);
DISPLAY 0.468085 (-5050 4525);
PAINT SKYBLUE (-5050 4525);
FORCEPROP 1 LAST CDS_LMAN_SYM_OUTLINE -600,1150,600,-1150
J 0
(-4450 3350);
DISPLAY 0.468085 (-4450 3350);
PAINT GREEN (-4450 3350);
DISPLAY INVISIBLE (-4450 3350);
FORCEPROP 1 LAST PATH I237
J 0
(-4450 3350);
DISPLAY 0.723404 (-4450 3350);
PAINT GREEN (-4450 3350);
DISPLAY INVISIBLE (-4450 3350);
FORCEPROP 1 LAST NEEDS_NO_SIZE TRUE
J 0
(-4450 3350);
DISPLAY 0.723404 (-4450 3350);
PAINT GREEN (-4450 3350);
DISPLAY INVISIBLE (-4450 3350);
FORCEPROP 2 LAST CDS_LIB pure_quanta
J 0
(-4450 3350);
DISPLAY INVISIBLE (-4450 3350);
FORCEADD GND..1
(-2900 5650);
FORCEPROP 3 LASTPIN (-2900 5700) SIG_NAME GND\g
J 0
(-2890 5710);
DISPLAY 0.659574 (-2890 5710);
PAINT MONO (-2890 5710);
DISPLAY INVISIBLE (-2890 5710);
FORCEPROP 2 LAST CDS_LIB pure_quanta_power
J 0
(-2900 5650);
DISPLAY INVISIBLE (-2900 5650);
FORCEPROP 2 LAST BOM_COST MEM
J 0
(-2875 5775);
DISPLAY 0.659574 (-2875 5775);
DISPLAY INVISIBLE (-2875 5775);
FORCEPROP 1 LAST SIZE 1B
J 0
(-2825 5600);
DISPLAY 0.723404 (-2825 5600);
PAINT GREEN (-2825 5600);
DISPLAY INVISIBLE (-2825 5600);
FORCEPROP 1 LAST PATH I238
J 0
(-2825 5650);
DISPLAY 0.872340 (-2825 5650);
PAINT AQUA (-2825 5650);
DISPLAY INVISIBLE (-2825 5650);
FORCEPROP 2 LAST ROOM MEM_EFGH_DECOUPLING_CAPS
J 0
(-2875 5725);
DISPLAY 0.659574 (-2875 5725);
PAINT RED (-2875 5725);
DISPLAY INVISIBLE (-2875 5725);
FORCEPROP 1 LAST HDL_POWER GND
J 0
(-2900 5800);
DISPLAY 0.723404 (-2900 5800);
PAINT GREEN (-2900 5800);
DISPLAY INVISIBLE (-2900 5800);
FORCEADD Q_CAP..1
R 2
(-2900 6000);
FORCEPROP 1 LAST LOCATION C159
J 2
(-2950 6100);
DISPLAY 0.489362 (-2950 6100);
PAINT SKYBLUE (-2950 6100);
FORCEPROP 0 LAST $SEC 1
J 0
(-2950 6150);
DISPLAY 0.680851 (-2950 6150);
PAINT MONO (-2950 6150);
DISPLAY INVISIBLE (-2950 6150);
FORCEPROP 0 LAST CDS_SEC 1
J 0
(-2950 6150);
DISPLAY 0.680851 (-2950 6150);
DISPLAY INVISIBLE (-2950 6150);
FORCEPROP 1 LASTPIN (-2900 6100) $PN 1
J 2
(-2910 6080);
DISPLAY 0.489362 (-2910 6080);
PAINT MONO (-2910 6080);
FORCEPROP 1 LASTPIN (-2900 5900) $PN 2
J 2
(-2910 5880);
DISPLAY 0.489362 (-2910 5880);
PAINT MONO (-2910 5880);
FORCEPROP 1 LAST MATERIAL X6S
J 2
(-2950 5900);
DISPLAY 0.489362 (-2950 5900);
PAINT SKYBLUE (-2950 5900);
FORCEPROP 1 LAST TOLERANCE 10%
J 2
(-2950 5950);
DISPLAY 0.489362 (-2950 5950);
PAINT SKYBLUE (-2950 5950);
FORCEPROP 1 LAST VALUE 10UF
J 2
(-2950 6050);
DISPLAY 0.489362 (-2950 6050);
PAINT SKYBLUE (-2950 6050);
FORCEPROP 1 LAST PART_NUMBER CH6104KEA00
J 2
(-2950 5850);
DISPLAY 0.489362 (-2950 5850);
PAINT SKYBLUE (-2950 5850);
FORCEPROP 1 LAST VOLTAGE 25V
J 2
(-2950 6000);
DISPLAY 0.489362 (-2950 6000);
PAINT SKYBLUE (-2950 6000);
FORCEPROP 1 LAST PACK_TYPE C0805
J 2
(-2950 5800);
DISPLAY 0.489362 (-2950 5800);
PAINT SKYBLUE (-2950 5800);
FORCEPROP 0 LAST BOM_COST MEM
J 2
(-2955 6145);
DISPLAY 0.595745 (-2955 6145);
PAINT MONO (-2955 6145);
DISPLAY INVISIBLE (-2955 6145);
FORCEPROP 2 LAST CDS_LIB pure_quanta
J 0
(-2900 6000);
DISPLAY INVISIBLE (-2900 6000);
FORCEPROP 1 LAST PATH I239
J 2
(-2950 6150);
DISPLAY 0.978723 (-2950 6150);
PAINT WHITE (-2950 6150);
DISPLAY INVISIBLE (-2950 6150);
FORCEPROP 0 LAST ROOM MEM_CH_A_CPU0_DIMM1
J 2
(-2955 6145);
DISPLAY 0.595745 (-2955 6145);
PAINT RED (-2955 6145);
DISPLAY INVISIBLE (-2955 6145);
FORCEADD TAP..1
R 2
(-7725 3200);
FORCEPROP 3 LASTPIN (-7675 3200) SIG_NAME M_H_CPU0_SB_CB<1>
J 0
(-7665 3210);
DISPLAY 0.659574 (-7665 3210);
PAINT MONO (-7665 3210);
DISPLAY INVISIBLE (-7665 3210);
FORCEPROP 1 LASTPIN (-7675 3200) BN 1
J 2
(-7663 3208);
DISPLAY 0.489362 (-7663 3208);
PAINT GREEN (-7663 3208);
FORCEPROP 2 LAST CDS_LIB mstr_standard
J 0
(-7725 3200);
DISPLAY 0.723404 (-7725 3200);
PAINT MONO (-7725 3200);
DISPLAY INVISIBLE (-7725 3200);
FORCEPROP 1 LAST BODY_TYPE PLUMBING
J 2
(-7725 3250);
DISPLAY 0.872340 (-7725 3250);
PAINT GREEN (-7725 3250);
DISPLAY INVISIBLE (-7725 3250);
FORCEPROP 1 LAST HDL_TAP TRUE
J 2
(-8050 3075);
DISPLAY 0.872340 (-8050 3075);
DISPLAY INVISIBLE (-8050 3075);
FORCEPROP 1 LAST PATH I24
J 2
(-7723 3200);
DISPLAY 0.872340 (-7723 3200);
PAINT GREEN (-7723 3200);
DISPLAY INVISIBLE (-7723 3200);
FORCEADD Q_CAP..1
R 2
(-2325 6000);
FORCEPROP 1 LAST LOCATION C161
J 2
(-2375 6100);
DISPLAY 0.489362 (-2375 6100);
PAINT SKYBLUE (-2375 6100);
FORCEPROP 0 LAST $SEC 1
J 0
(-2375 6150);
DISPLAY 0.680851 (-2375 6150);
PAINT MONO (-2375 6150);
DISPLAY INVISIBLE (-2375 6150);
FORCEPROP 0 LAST CDS_SEC 1
J 0
(-2375 6150);
DISPLAY 0.680851 (-2375 6150);
DISPLAY INVISIBLE (-2375 6150);
FORCEPROP 1 LASTPIN (-2325 6100) $PN 1
J 2
(-2335 6080);
DISPLAY 0.489362 (-2335 6080);
PAINT MONO (-2335 6080);
FORCEPROP 1 LASTPIN (-2325 5900) $PN 2
J 2
(-2335 5880);
DISPLAY 0.489362 (-2335 5880);
PAINT MONO (-2335 5880);
FORCEPROP 1 LAST VALUE 10UF
J 2
(-2375 6050);
DISPLAY 0.489362 (-2375 6050);
PAINT SKYBLUE (-2375 6050);
FORCEPROP 1 LAST VOLTAGE 25V
J 2
(-2375 6000);
DISPLAY 0.489362 (-2375 6000);
PAINT SKYBLUE (-2375 6000);
FORCEPROP 1 LAST PACK_TYPE C0805
J 2
(-2375 5800);
DISPLAY 0.489362 (-2375 5800);
PAINT SKYBLUE (-2375 5800);
FORCEPROP 1 LAST TOLERANCE 10%
J 2
(-2375 5950);
DISPLAY 0.489362 (-2375 5950);
PAINT SKYBLUE (-2375 5950);
FORCEPROP 1 LAST MATERIAL X6S
J 2
(-2375 5900);
DISPLAY 0.489362 (-2375 5900);
PAINT SKYBLUE (-2375 5900);
FORCEPROP 1 LAST PART_NUMBER CH6104KEA00
J 2
(-2375 5850);
DISPLAY 0.489362 (-2375 5850);
PAINT SKYBLUE (-2375 5850);
FORCEPROP 0 LAST BOM_COST MEM
J 2
(-2380 6145);
DISPLAY 0.595745 (-2380 6145);
PAINT MONO (-2380 6145);
DISPLAY INVISIBLE (-2380 6145);
FORCEPROP 2 LAST CDS_LIB pure_quanta
J 0
(-2325 6000);
DISPLAY INVISIBLE (-2325 6000);
FORCEPROP 1 LAST PATH I240
J 2
(-2375 6150);
DISPLAY 0.978723 (-2375 6150);
PAINT WHITE (-2375 6150);
DISPLAY INVISIBLE (-2375 6150);
FORCEPROP 0 LAST ROOM MEM_CH_A_CPU0_DIMM1
J 2
(-2380 6145);
DISPLAY 0.595745 (-2380 6145);
PAINT RED (-2380 6145);
DISPLAY INVISIBLE (-2380 6145);
FORCEADD UNIVERSAL_POWER..1
(-2900 6325);
FORCEPROP 3 LASTPIN (-2900 6275) SIG_NAME P12V_MEM_0\g
J 0
(-2890 6285);
DISPLAY 0.659574 (-2890 6285);
PAINT MONO (-2890 6285);
DISPLAY INVISIBLE (-2890 6285);
FORCEPROP 1 LAST HDL_POWER P12V_MEM_0
J 1
(-2925 6375);
DISPLAY 0.489362 (-2925 6375);
PAINT GREEN (-2925 6375);
FORCEPROP 2 LAST BOM_COST VR_SYSTEM
J 0
(-2900 6425);
DISPLAY 0.617021 (-2900 6425);
PAINT PURPLE (-2900 6425);
DISPLAY INVISIBLE (-2900 6425);
FORCEPROP 2 LAST CDS_LIB pure_quanta_power
J 0
(-2900 6325);
DISPLAY INVISIBLE (-2900 6325);
FORCEPROP 1 LAST PATH I241
J 0
(-2850 6350);
DISPLAY 0.872340 (-2850 6350);
PAINT AQUA (-2850 6350);
DISPLAY INVISIBLE (-2850 6350);
FORCEADD OFFPAGE..1
(-8325 2650);
FORCEPROP 2 LAST $XR5 96 
J 0
(-9027 2650);
DISPLAY 0.638298 (-9027 2650);
PAINT MONO (-9027 2650);
FORCEPROP 2 LAST $XR4 95 
J 0
(-8937 2650);
DISPLAY 0.638298 (-8937 2650);
PAINT MONO (-8937 2650);
FORCEPROP 2 LAST $XR3 94 
J 0
(-8847 2650);
DISPLAY 0.638298 (-8847 2650);
PAINT MONO (-8847 2650);
FORCEPROP 2 LAST $XR2 93 
J 0
(-8757 2650);
DISPLAY 0.638298 (-8757 2650);
PAINT MONO (-8757 2650);
FORCEPROP 2 LAST $XR1 91 
J 0
(-8667 2650);
DISPLAY 0.638298 (-8667 2650);
PAINT MONO (-8667 2650);
FORCEPROP 2 LAST $XR0 136 
J 0
(-8577 2650);
DISPLAY 0.638298 (-8577 2650);
PAINT MONO (-8577 2650);
FORCEPROP 2 LAST PATH I242
J 0
(-8600 2700);
DISPLAY 0.680851 (-8600 2700);
DISPLAY INVISIBLE (-8600 2700);
FORCEPROP 1 LAST COMMENT_BODY TRUE
J 0
(-8200 2550);
DISPLAY 0.872340 (-8200 2550);
PAINT GREEN (-8200 2550);
DISPLAY INVISIBLE (-8200 2550);
FORCEPROP 1 LAST OFFPAGE TRUE
J 0
(-8000 2525);
DISPLAY 0.872340 (-8000 2525);
PAINT GREEN (-8000 2525);
DISPLAY INVISIBLE (-8000 2525);
FORCEPROP 2 LAST CDS_LIB mstr_standard
J 0
(-8325 2650);
DISPLAY 0.808511 (-8325 2650);
DISPLAY INVISIBLE (-8325 2650);
FORCEADD Q_RES..1
(-7775 2650);
FORCEPROP 1 LAST $LOCATION R1575
J 0
(-7825 2675);
DISPLAY 0.510638 (-7825 2675);
PAINT SKYBLUE (-7825 2675);
FORCEPROP 0 LAST CDS_LOCATION R1575
J 0
(-7825 2750);
DISPLAY 0.680851 (-7825 2750);
DISPLAY INVISIBLE (-7825 2750);
FORCEPROP 0 LAST $SEC 1
J 0
(-7825 2750);
DISPLAY 0.680851 (-7825 2750);
PAINT MONO (-7825 2750);
DISPLAY INVISIBLE (-7825 2750);
FORCEPROP 0 LAST CDS_SEC 1
J 0
(-7825 2750);
DISPLAY 0.680851 (-7825 2750);
DISPLAY INVISIBLE (-7825 2750);
FORCEPROP 1 LASTPIN (-7875 2650) $PN 1
J 0
(-7863 2662);
DISPLAY 0.787234 (-7863 2662);
PAINT MONO (-7863 2662);
FORCEPROP 1 LASTPIN (-7675 2650) $PN 2
J 0
(-7713 2662);
DISPLAY 0.787234 (-7713 2662);
PAINT MONO (-7713 2662);
FORCEPROP 1 LAST VALUE 49.9
J 2
(-7600 2700);
DISPLAY 0.510638 (-7600 2700);
PAINT SKYBLUE (-7600 2700);
FORCEPROP 2 LAST CDS_LIB pure_quanta
J 0
(-7775 2650);
DISPLAY INVISIBLE (-7775 2650);
FORCEPROP 1 LAST PATH I243
J 0
(-7825 2800);
DISPLAY 0.978723 (-7825 2800);
PAINT WHITE (-7825 2800);
DISPLAY INVISIBLE (-7825 2800);
FORCEPROP 1 LAST PART_NUMBER CS04992FB07
J 0
(-7825 2750);
DISPLAY 0.978723 (-7825 2750);
DISPLAY INVISIBLE (-7825 2750);
FORCEPROP 1 LAST TOLERANCE 1%
J 0
(-7775 2550);
DISPLAY 0.978723 (-7775 2550);
DISPLAY INVISIBLE (-7775 2550);
FORCEPROP 1 LAST WATTAGE 1/16W
J 2
(-7800 2500);
DISPLAY 0.978723 (-7800 2500);
DISPLAY INVISIBLE (-7800 2500);
FORCEPROP 1 LAST PACK_TYPE 0402LF
J 0
(-7525 2500);
DISPLAY 0.978723 (-7525 2500);
DISPLAY INVISIBLE (-7525 2500);
FORCEPROP 1 LAST MATERIAL CHIP
J 0
(-7775 2500);
DISPLAY 0.978723 (-7775 2500);
DISPLAY INVISIBLE (-7775 2500);
FORCEADD TAP..1
R 2
(-7725 3250);
FORCEPROP 3 LASTPIN (-7675 3250) SIG_NAME M_H_CPU0_SB_CB<2>
J 0
(-7665 3260);
DISPLAY 0.659574 (-7665 3260);
PAINT MONO (-7665 3260);
DISPLAY INVISIBLE (-7665 3260);
FORCEPROP 1 LASTPIN (-7675 3250) BN 2
J 2
(-7663 3258);
DISPLAY 0.489362 (-7663 3258);
PAINT GREEN (-7663 3258);
FORCEPROP 2 LAST CDS_LIB mstr_standard
J 0
(-7725 3250);
DISPLAY 0.723404 (-7725 3250);
PAINT MONO (-7725 3250);
DISPLAY INVISIBLE (-7725 3250);
FORCEPROP 1 LAST BODY_TYPE PLUMBING
J 2
(-7725 3300);
DISPLAY 0.872340 (-7725 3300);
PAINT GREEN (-7725 3300);
DISPLAY INVISIBLE (-7725 3300);
FORCEPROP 1 LAST HDL_TAP TRUE
J 2
(-8050 3125);
DISPLAY 0.872340 (-8050 3125);
DISPLAY INVISIBLE (-8050 3125);
FORCEPROP 1 LAST PATH I25
J 2
(-7723 3250);
DISPLAY 0.872340 (-7723 3250);
PAINT GREEN (-7723 3250);
DISPLAY INVISIBLE (-7723 3250);
FORCEADD TAP..1
R 2
(-7725 3300);
FORCEPROP 3 LASTPIN (-7675 3300) SIG_NAME M_H_CPU0_SB_CB<3>
J 0
(-7665 3310);
DISPLAY 0.659574 (-7665 3310);
PAINT MONO (-7665 3310);
DISPLAY INVISIBLE (-7665 3310);
FORCEPROP 1 LASTPIN (-7675 3300) BN 3
J 2
(-7663 3308);
DISPLAY 0.489362 (-7663 3308);
PAINT GREEN (-7663 3308);
FORCEPROP 2 LAST CDS_LIB mstr_standard
J 0
(-7725 3300);
DISPLAY 0.723404 (-7725 3300);
PAINT MONO (-7725 3300);
DISPLAY INVISIBLE (-7725 3300);
FORCEPROP 1 LAST BODY_TYPE PLUMBING
J 2
(-7725 3350);
DISPLAY 0.872340 (-7725 3350);
PAINT GREEN (-7725 3350);
DISPLAY INVISIBLE (-7725 3350);
FORCEPROP 1 LAST HDL_TAP TRUE
J 2
(-8050 3175);
DISPLAY 0.872340 (-8050 3175);
DISPLAY INVISIBLE (-8050 3175);
FORCEPROP 1 LAST PATH I26
J 2
(-7723 3300);
DISPLAY 0.872340 (-7723 3300);
PAINT GREEN (-7723 3300);
DISPLAY INVISIBLE (-7723 3300);
FORCEADD TAP..1
R 2
(-7725 3350);
FORCEPROP 3 LASTPIN (-7675 3350) SIG_NAME M_H_CPU0_SB_CB<4>
J 0
(-7665 3360);
DISPLAY 0.659574 (-7665 3360);
PAINT MONO (-7665 3360);
DISPLAY INVISIBLE (-7665 3360);
FORCEPROP 1 LASTPIN (-7675 3350) BN 4
J 2
(-7663 3358);
DISPLAY 0.489362 (-7663 3358);
PAINT GREEN (-7663 3358);
FORCEPROP 2 LAST CDS_LIB mstr_standard
J 0
(-7725 3350);
DISPLAY 0.723404 (-7725 3350);
PAINT MONO (-7725 3350);
DISPLAY INVISIBLE (-7725 3350);
FORCEPROP 1 LAST BODY_TYPE PLUMBING
J 2
(-7725 3400);
DISPLAY 0.872340 (-7725 3400);
PAINT GREEN (-7725 3400);
DISPLAY INVISIBLE (-7725 3400);
FORCEPROP 1 LAST HDL_TAP TRUE
J 2
(-8050 3225);
DISPLAY 0.872340 (-8050 3225);
DISPLAY INVISIBLE (-8050 3225);
FORCEPROP 1 LAST PATH I27
J 2
(-7723 3350);
DISPLAY 0.872340 (-7723 3350);
PAINT GREEN (-7723 3350);
DISPLAY INVISIBLE (-7723 3350);
FORCEADD TAP..1
R 2
(-7725 3450);
FORCEPROP 3 LASTPIN (-7675 3450) SIG_NAME M_H_CPU0_SB_CB<6>
J 0
(-7665 3460);
DISPLAY 0.659574 (-7665 3460);
PAINT MONO (-7665 3460);
DISPLAY INVISIBLE (-7665 3460);
FORCEPROP 1 LASTPIN (-7675 3450) BN 6
J 2
(-7663 3458);
DISPLAY 0.489362 (-7663 3458);
PAINT GREEN (-7663 3458);
FORCEPROP 2 LAST CDS_LIB mstr_standard
J 0
(-7725 3450);
DISPLAY 0.723404 (-7725 3450);
PAINT MONO (-7725 3450);
DISPLAY INVISIBLE (-7725 3450);
FORCEPROP 1 LAST BODY_TYPE PLUMBING
J 2
(-7725 3500);
DISPLAY 0.872340 (-7725 3500);
PAINT GREEN (-7725 3500);
DISPLAY INVISIBLE (-7725 3500);
FORCEPROP 1 LAST HDL_TAP TRUE
J 2
(-8050 3325);
DISPLAY 0.872340 (-8050 3325);
DISPLAY INVISIBLE (-8050 3325);
FORCEPROP 1 LAST PATH I28
J 2
(-7723 3450);
DISPLAY 0.872340 (-7723 3450);
PAINT GREEN (-7723 3450);
DISPLAY INVISIBLE (-7723 3450);
FORCEADD TAP..1
R 2
(-7725 3400);
FORCEPROP 3 LASTPIN (-7675 3400) SIG_NAME M_H_CPU0_SB_CB<5>
J 0
(-7665 3410);
DISPLAY 0.659574 (-7665 3410);
PAINT MONO (-7665 3410);
DISPLAY INVISIBLE (-7665 3410);
FORCEPROP 1 LASTPIN (-7675 3400) BN 5
J 2
(-7663 3408);
DISPLAY 0.489362 (-7663 3408);
PAINT GREEN (-7663 3408);
FORCEPROP 2 LAST CDS_LIB mstr_standard
J 0
(-7725 3400);
DISPLAY 0.723404 (-7725 3400);
PAINT MONO (-7725 3400);
DISPLAY INVISIBLE (-7725 3400);
FORCEPROP 1 LAST BODY_TYPE PLUMBING
J 2
(-7725 3450);
DISPLAY 0.872340 (-7725 3450);
PAINT GREEN (-7725 3450);
DISPLAY INVISIBLE (-7725 3450);
FORCEPROP 1 LAST HDL_TAP TRUE
J 2
(-8050 3275);
DISPLAY 0.872340 (-8050 3275);
DISPLAY INVISIBLE (-8050 3275);
FORCEPROP 1 LAST PATH I29
J 2
(-7723 3400);
DISPLAY 0.872340 (-7723 3400);
PAINT GREEN (-7723 3400);
DISPLAY INVISIBLE (-7723 3400);
FORCEADD TAP..1
R 2
(-7725 3500);
FORCEPROP 3 LASTPIN (-7675 3500) SIG_NAME M_H_CPU0_SB_CB<7>
J 0
(-7665 3510);
DISPLAY 0.659574 (-7665 3510);
PAINT MONO (-7665 3510);
DISPLAY INVISIBLE (-7665 3510);
FORCEPROP 1 LASTPIN (-7675 3500) BN 7
J 2
(-7663 3508);
DISPLAY 0.489362 (-7663 3508);
PAINT GREEN (-7663 3508);
FORCEPROP 2 LAST CDS_LIB mstr_standard
J 0
(-7725 3500);
DISPLAY 0.723404 (-7725 3500);
PAINT MONO (-7725 3500);
DISPLAY INVISIBLE (-7725 3500);
FORCEPROP 1 LAST BODY_TYPE PLUMBING
J 2
(-7725 3550);
DISPLAY 0.872340 (-7725 3550);
PAINT GREEN (-7725 3550);
DISPLAY INVISIBLE (-7725 3550);
FORCEPROP 1 LAST HDL_TAP TRUE
J 2
(-8050 3375);
DISPLAY 0.872340 (-8050 3375);
DISPLAY INVISIBLE (-8050 3375);
FORCEPROP 1 LAST PATH I30
J 2
(-7723 3500);
DISPLAY 0.872340 (-7723 3500);
PAINT GREEN (-7723 3500);
DISPLAY INVISIBLE (-7723 3500);
FORCEADD TAP..1
R 2
(-7725 3600);
FORCEPROP 3 LASTPIN (-7675 3600) SIG_NAME M_H_CPU0_SA_CB<0>
J 0
(-7665 3610);
DISPLAY 0.659574 (-7665 3610);
PAINT MONO (-7665 3610);
DISPLAY INVISIBLE (-7665 3610);
FORCEPROP 1 LASTPIN (-7675 3600) BN 0
J 2
(-7663 3608);
DISPLAY 0.489362 (-7663 3608);
PAINT GREEN (-7663 3608);
FORCEPROP 2 LAST CDS_LIB mstr_standard
J 0
(-7725 3600);
DISPLAY 0.723404 (-7725 3600);
PAINT MONO (-7725 3600);
DISPLAY INVISIBLE (-7725 3600);
FORCEPROP 1 LAST BODY_TYPE PLUMBING
J 2
(-7725 3650);
DISPLAY 0.872340 (-7725 3650);
PAINT GREEN (-7725 3650);
DISPLAY INVISIBLE (-7725 3650);
FORCEPROP 1 LAST HDL_TAP TRUE
J 2
(-8050 3475);
DISPLAY 0.872340 (-8050 3475);
DISPLAY INVISIBLE (-8050 3475);
FORCEPROP 1 LAST PATH I31
J 2
(-7723 3600);
DISPLAY 0.872340 (-7723 3600);
PAINT GREEN (-7723 3600);
DISPLAY INVISIBLE (-7723 3600);
FORCEADD TAP..1
R 2
(-7725 3650);
FORCEPROP 3 LASTPIN (-7675 3650) SIG_NAME M_H_CPU0_SA_CB<1>
J 0
(-7665 3660);
DISPLAY 0.659574 (-7665 3660);
PAINT MONO (-7665 3660);
DISPLAY INVISIBLE (-7665 3660);
FORCEPROP 1 LASTPIN (-7675 3650) BN 1
J 2
(-7663 3658);
DISPLAY 0.489362 (-7663 3658);
PAINT GREEN (-7663 3658);
FORCEPROP 2 LAST CDS_LIB mstr_standard
J 0
(-7725 3650);
DISPLAY 0.723404 (-7725 3650);
PAINT MONO (-7725 3650);
DISPLAY INVISIBLE (-7725 3650);
FORCEPROP 1 LAST BODY_TYPE PLUMBING
J 2
(-7725 3700);
DISPLAY 0.872340 (-7725 3700);
PAINT GREEN (-7725 3700);
DISPLAY INVISIBLE (-7725 3700);
FORCEPROP 1 LAST HDL_TAP TRUE
J 2
(-8050 3525);
DISPLAY 0.872340 (-8050 3525);
DISPLAY INVISIBLE (-8050 3525);
FORCEPROP 1 LAST PATH I32
J 2
(-7723 3650);
DISPLAY 0.872340 (-7723 3650);
PAINT GREEN (-7723 3650);
DISPLAY INVISIBLE (-7723 3650);
FORCEADD TAP..1
R 2
(-7725 3700);
FORCEPROP 3 LASTPIN (-7675 3700) SIG_NAME M_H_CPU0_SA_CB<2>
J 0
(-7665 3710);
DISPLAY 0.659574 (-7665 3710);
PAINT MONO (-7665 3710);
DISPLAY INVISIBLE (-7665 3710);
FORCEPROP 1 LASTPIN (-7675 3700) BN 2
J 2
(-7663 3708);
DISPLAY 0.489362 (-7663 3708);
PAINT GREEN (-7663 3708);
FORCEPROP 2 LAST CDS_LIB mstr_standard
J 0
(-7725 3700);
DISPLAY 0.723404 (-7725 3700);
PAINT MONO (-7725 3700);
DISPLAY INVISIBLE (-7725 3700);
FORCEPROP 1 LAST BODY_TYPE PLUMBING
J 2
(-7725 3750);
DISPLAY 0.872340 (-7725 3750);
PAINT GREEN (-7725 3750);
DISPLAY INVISIBLE (-7725 3750);
FORCEPROP 1 LAST HDL_TAP TRUE
J 2
(-8050 3575);
DISPLAY 0.872340 (-8050 3575);
DISPLAY INVISIBLE (-8050 3575);
FORCEPROP 1 LAST PATH I33
J 2
(-7723 3700);
DISPLAY 0.872340 (-7723 3700);
PAINT GREEN (-7723 3700);
DISPLAY INVISIBLE (-7723 3700);
FORCEADD TAP..1
R 2
(-7725 3750);
FORCEPROP 3 LASTPIN (-7675 3750) SIG_NAME M_H_CPU0_SA_CB<3>
J 0
(-7665 3760);
DISPLAY 0.659574 (-7665 3760);
PAINT MONO (-7665 3760);
DISPLAY INVISIBLE (-7665 3760);
FORCEPROP 1 LASTPIN (-7675 3750) BN 3
J 2
(-7663 3758);
DISPLAY 0.489362 (-7663 3758);
PAINT GREEN (-7663 3758);
FORCEPROP 2 LAST CDS_LIB mstr_standard
J 0
(-7725 3750);
DISPLAY 0.723404 (-7725 3750);
PAINT MONO (-7725 3750);
DISPLAY INVISIBLE (-7725 3750);
FORCEPROP 1 LAST BODY_TYPE PLUMBING
J 2
(-7725 3800);
DISPLAY 0.872340 (-7725 3800);
PAINT GREEN (-7725 3800);
DISPLAY INVISIBLE (-7725 3800);
FORCEPROP 1 LAST HDL_TAP TRUE
J 2
(-8050 3625);
DISPLAY 0.872340 (-8050 3625);
DISPLAY INVISIBLE (-8050 3625);
FORCEPROP 1 LAST PATH I34
J 2
(-7723 3750);
DISPLAY 0.872340 (-7723 3750);
PAINT GREEN (-7723 3750);
DISPLAY INVISIBLE (-7723 3750);
FORCEADD TAP..1
(-6025 2150);
FORCEPROP 3 LASTPIN (-6075 2150) SIG_NAME M_H_CPU0_SB_DQ<0>
J 0
(-6065 2160);
DISPLAY 0.659574 (-6065 2160);
PAINT MONO (-6065 2160);
DISPLAY INVISIBLE (-6065 2160);
FORCEPROP 1 LASTPIN (-6075 2150) BN 0
J 0
(-6087 2158);
DISPLAY 0.489362 (-6087 2158);
PAINT GREEN (-6087 2158);
FORCEPROP 2 LAST CDS_LIB mstr_standard
J 0
(-6025 2150);
DISPLAY 0.723404 (-6025 2150);
PAINT MONO (-6025 2150);
DISPLAY INVISIBLE (-6025 2150);
FORCEPROP 1 LAST BODY_TYPE PLUMBING
J 0
(-6025 2200);
DISPLAY 0.872340 (-6025 2200);
PAINT GREEN (-6025 2200);
DISPLAY INVISIBLE (-6025 2200);
FORCEPROP 1 LAST HDL_TAP TRUE
J 0
(-5700 2025);
DISPLAY 0.872340 (-5700 2025);
DISPLAY INVISIBLE (-5700 2025);
FORCEPROP 1 LAST PATH I35
J 0
(-6027 2150);
DISPLAY 0.872340 (-6027 2150);
PAINT GREEN (-6027 2150);
DISPLAY INVISIBLE (-6027 2150);
FORCEADD TAP..1
(-6025 2200);
FORCEPROP 3 LASTPIN (-6075 2200) SIG_NAME M_H_CPU0_SB_DQ<1>
J 0
(-6065 2210);
DISPLAY 0.659574 (-6065 2210);
PAINT MONO (-6065 2210);
DISPLAY INVISIBLE (-6065 2210);
FORCEPROP 1 LASTPIN (-6075 2200) BN 1
J 0
(-6087 2208);
DISPLAY 0.489362 (-6087 2208);
PAINT GREEN (-6087 2208);
FORCEPROP 2 LAST CDS_LIB mstr_standard
J 0
(-6025 2200);
DISPLAY 0.723404 (-6025 2200);
PAINT MONO (-6025 2200);
DISPLAY INVISIBLE (-6025 2200);
FORCEPROP 1 LAST BODY_TYPE PLUMBING
J 0
(-6025 2250);
DISPLAY 0.872340 (-6025 2250);
PAINT GREEN (-6025 2250);
DISPLAY INVISIBLE (-6025 2250);
FORCEPROP 1 LAST HDL_TAP TRUE
J 0
(-5700 2075);
DISPLAY 0.872340 (-5700 2075);
DISPLAY INVISIBLE (-5700 2075);
FORCEPROP 1 LAST PATH I36
J 0
(-6027 2200);
DISPLAY 0.872340 (-6027 2200);
PAINT GREEN (-6027 2200);
DISPLAY INVISIBLE (-6027 2200);
FORCEADD TAP..1
(-6025 2250);
FORCEPROP 3 LASTPIN (-6075 2250) SIG_NAME M_H_CPU0_SB_DQ<2>
J 0
(-6065 2260);
DISPLAY 0.659574 (-6065 2260);
PAINT MONO (-6065 2260);
DISPLAY INVISIBLE (-6065 2260);
FORCEPROP 1 LASTPIN (-6075 2250) BN 2
J 0
(-6087 2258);
DISPLAY 0.489362 (-6087 2258);
PAINT GREEN (-6087 2258);
FORCEPROP 2 LAST CDS_LIB mstr_standard
J 0
(-6025 2250);
DISPLAY 0.723404 (-6025 2250);
PAINT MONO (-6025 2250);
DISPLAY INVISIBLE (-6025 2250);
FORCEPROP 1 LAST BODY_TYPE PLUMBING
J 0
(-6025 2300);
DISPLAY 0.872340 (-6025 2300);
PAINT GREEN (-6025 2300);
DISPLAY INVISIBLE (-6025 2300);
FORCEPROP 1 LAST HDL_TAP TRUE
J 0
(-5700 2125);
DISPLAY 0.872340 (-5700 2125);
DISPLAY INVISIBLE (-5700 2125);
FORCEPROP 1 LAST PATH I37
J 0
(-6027 2250);
DISPLAY 0.872340 (-6027 2250);
PAINT GREEN (-6027 2250);
DISPLAY INVISIBLE (-6027 2250);
FORCEADD TAP..1
(-6025 2300);
FORCEPROP 3 LASTPIN (-6075 2300) SIG_NAME M_H_CPU0_SB_DQ<3>
J 0
(-6065 2310);
DISPLAY 0.659574 (-6065 2310);
PAINT MONO (-6065 2310);
DISPLAY INVISIBLE (-6065 2310);
FORCEPROP 1 LASTPIN (-6075 2300) BN 3
J 0
(-6087 2308);
DISPLAY 0.489362 (-6087 2308);
PAINT GREEN (-6087 2308);
FORCEPROP 2 LAST CDS_LIB mstr_standard
J 0
(-6025 2300);
DISPLAY 0.723404 (-6025 2300);
PAINT MONO (-6025 2300);
DISPLAY INVISIBLE (-6025 2300);
FORCEPROP 1 LAST BODY_TYPE PLUMBING
J 0
(-6025 2350);
DISPLAY 0.872340 (-6025 2350);
PAINT GREEN (-6025 2350);
DISPLAY INVISIBLE (-6025 2350);
FORCEPROP 1 LAST HDL_TAP TRUE
J 0
(-5700 2175);
DISPLAY 0.872340 (-5700 2175);
DISPLAY INVISIBLE (-5700 2175);
FORCEPROP 1 LAST PATH I38
J 0
(-6027 2300);
DISPLAY 0.872340 (-6027 2300);
PAINT GREEN (-6027 2300);
DISPLAY INVISIBLE (-6027 2300);
FORCEADD TAP..1
(-6025 2350);
FORCEPROP 3 LASTPIN (-6075 2350) SIG_NAME M_H_CPU0_SB_DQ<4>
J 0
(-6065 2360);
DISPLAY 0.659574 (-6065 2360);
PAINT MONO (-6065 2360);
DISPLAY INVISIBLE (-6065 2360);
FORCEPROP 1 LASTPIN (-6075 2350) BN 4
J 0
(-6087 2358);
DISPLAY 0.489362 (-6087 2358);
PAINT GREEN (-6087 2358);
FORCEPROP 2 LAST CDS_LIB mstr_standard
J 0
(-6025 2350);
DISPLAY 0.723404 (-6025 2350);
PAINT MONO (-6025 2350);
DISPLAY INVISIBLE (-6025 2350);
FORCEPROP 1 LAST BODY_TYPE PLUMBING
J 0
(-6025 2400);
DISPLAY 0.872340 (-6025 2400);
PAINT GREEN (-6025 2400);
DISPLAY INVISIBLE (-6025 2400);
FORCEPROP 1 LAST HDL_TAP TRUE
J 0
(-5700 2225);
DISPLAY 0.872340 (-5700 2225);
DISPLAY INVISIBLE (-5700 2225);
FORCEPROP 1 LAST PATH I39
J 0
(-6027 2350);
DISPLAY 0.872340 (-6027 2350);
PAINT GREEN (-6027 2350);
DISPLAY INVISIBLE (-6027 2350);
FORCEADD TAP..1
(-6025 2400);
FORCEPROP 3 LASTPIN (-6075 2400) SIG_NAME M_H_CPU0_SB_DQ<5>
J 0
(-6065 2410);
DISPLAY 0.659574 (-6065 2410);
PAINT MONO (-6065 2410);
DISPLAY INVISIBLE (-6065 2410);
FORCEPROP 1 LASTPIN (-6075 2400) BN 5
J 0
(-6087 2408);
DISPLAY 0.489362 (-6087 2408);
PAINT GREEN (-6087 2408);
FORCEPROP 2 LAST CDS_LIB mstr_standard
J 0
(-6025 2400);
DISPLAY 0.723404 (-6025 2400);
PAINT MONO (-6025 2400);
DISPLAY INVISIBLE (-6025 2400);
FORCEPROP 1 LAST BODY_TYPE PLUMBING
J 0
(-6025 2450);
DISPLAY 0.872340 (-6025 2450);
PAINT GREEN (-6025 2450);
DISPLAY INVISIBLE (-6025 2450);
FORCEPROP 1 LAST HDL_TAP TRUE
J 0
(-5700 2275);
DISPLAY 0.872340 (-5700 2275);
DISPLAY INVISIBLE (-5700 2275);
FORCEPROP 1 LAST PATH I40
J 0
(-6027 2400);
DISPLAY 0.872340 (-6027 2400);
PAINT GREEN (-6027 2400);
DISPLAY INVISIBLE (-6027 2400);
FORCEADD TAP..1
(-6025 2450);
FORCEPROP 3 LASTPIN (-6075 2450) SIG_NAME M_H_CPU0_SB_DQ<6>
J 0
(-6065 2460);
DISPLAY 0.659574 (-6065 2460);
PAINT MONO (-6065 2460);
DISPLAY INVISIBLE (-6065 2460);
FORCEPROP 1 LASTPIN (-6075 2450) BN 6
J 0
(-6087 2458);
DISPLAY 0.489362 (-6087 2458);
PAINT GREEN (-6087 2458);
FORCEPROP 2 LAST CDS_LIB mstr_standard
J 0
(-6025 2450);
DISPLAY 0.723404 (-6025 2450);
PAINT MONO (-6025 2450);
DISPLAY INVISIBLE (-6025 2450);
FORCEPROP 1 LAST BODY_TYPE PLUMBING
J 0
(-6025 2500);
DISPLAY 0.872340 (-6025 2500);
PAINT GREEN (-6025 2500);
DISPLAY INVISIBLE (-6025 2500);
FORCEPROP 1 LAST HDL_TAP TRUE
J 0
(-5700 2325);
DISPLAY 0.872340 (-5700 2325);
DISPLAY INVISIBLE (-5700 2325);
FORCEPROP 1 LAST PATH I41
J 0
(-6027 2450);
DISPLAY 0.872340 (-6027 2450);
PAINT GREEN (-6027 2450);
DISPLAY INVISIBLE (-6027 2450);
FORCEADD TAP..1
(-6025 2500);
FORCEPROP 3 LASTPIN (-6075 2500) SIG_NAME M_H_CPU0_SB_DQ<7>
J 0
(-6065 2510);
DISPLAY 0.659574 (-6065 2510);
PAINT MONO (-6065 2510);
DISPLAY INVISIBLE (-6065 2510);
FORCEPROP 1 LASTPIN (-6075 2500) BN 7
J 0
(-6087 2508);
DISPLAY 0.489362 (-6087 2508);
PAINT GREEN (-6087 2508);
FORCEPROP 2 LAST CDS_LIB mstr_standard
J 0
(-6025 2500);
DISPLAY 0.723404 (-6025 2500);
PAINT MONO (-6025 2500);
DISPLAY INVISIBLE (-6025 2500);
FORCEPROP 1 LAST BODY_TYPE PLUMBING
J 0
(-6025 2550);
DISPLAY 0.872340 (-6025 2550);
PAINT GREEN (-6025 2550);
DISPLAY INVISIBLE (-6025 2550);
FORCEPROP 1 LAST HDL_TAP TRUE
J 0
(-5700 2375);
DISPLAY 0.872340 (-5700 2375);
DISPLAY INVISIBLE (-5700 2375);
FORCEPROP 1 LAST PATH I42
J 0
(-6027 2500);
DISPLAY 0.872340 (-6027 2500);
PAINT GREEN (-6027 2500);
DISPLAY INVISIBLE (-6027 2500);
FORCEADD TAP..1
(-6025 2550);
FORCEPROP 3 LASTPIN (-6075 2550) SIG_NAME M_H_CPU0_SB_DQ<8>
J 0
(-6065 2560);
DISPLAY 0.659574 (-6065 2560);
PAINT MONO (-6065 2560);
DISPLAY INVISIBLE (-6065 2560);
FORCEPROP 1 LASTPIN (-6075 2550) BN 8
J 0
(-6087 2558);
DISPLAY 0.489362 (-6087 2558);
PAINT GREEN (-6087 2558);
FORCEPROP 2 LAST CDS_LIB mstr_standard
J 0
(-6025 2550);
DISPLAY 0.723404 (-6025 2550);
PAINT MONO (-6025 2550);
DISPLAY INVISIBLE (-6025 2550);
FORCEPROP 1 LAST BODY_TYPE PLUMBING
J 0
(-6025 2600);
DISPLAY 0.872340 (-6025 2600);
PAINT GREEN (-6025 2600);
DISPLAY INVISIBLE (-6025 2600);
FORCEPROP 1 LAST HDL_TAP TRUE
J 0
(-5700 2425);
DISPLAY 0.872340 (-5700 2425);
DISPLAY INVISIBLE (-5700 2425);
FORCEPROP 1 LAST PATH I43
J 0
(-6027 2550);
DISPLAY 0.872340 (-6027 2550);
PAINT GREEN (-6027 2550);
DISPLAY INVISIBLE (-6027 2550);
FORCEADD TAP..1
(-6025 2600);
FORCEPROP 3 LASTPIN (-6075 2600) SIG_NAME M_H_CPU0_SB_DQ<9>
J 0
(-6065 2610);
DISPLAY 0.659574 (-6065 2610);
PAINT MONO (-6065 2610);
DISPLAY INVISIBLE (-6065 2610);
FORCEPROP 1 LASTPIN (-6075 2600) BN 9
J 0
(-6087 2608);
DISPLAY 0.489362 (-6087 2608);
PAINT GREEN (-6087 2608);
FORCEPROP 2 LAST CDS_LIB mstr_standard
J 0
(-6025 2600);
DISPLAY 0.723404 (-6025 2600);
PAINT MONO (-6025 2600);
DISPLAY INVISIBLE (-6025 2600);
FORCEPROP 1 LAST BODY_TYPE PLUMBING
J 0
(-6025 2650);
DISPLAY 0.872340 (-6025 2650);
PAINT GREEN (-6025 2650);
DISPLAY INVISIBLE (-6025 2650);
FORCEPROP 1 LAST HDL_TAP TRUE
J 0
(-5700 2475);
DISPLAY 0.872340 (-5700 2475);
DISPLAY INVISIBLE (-5700 2475);
FORCEPROP 1 LAST PATH I44
J 0
(-6027 2600);
DISPLAY 0.872340 (-6027 2600);
PAINT GREEN (-6027 2600);
DISPLAY INVISIBLE (-6027 2600);
FORCEADD TAP..1
(-6025 2650);
FORCEPROP 3 LASTPIN (-6075 2650) SIG_NAME M_H_CPU0_SB_DQ<10>
J 0
(-6065 2660);
DISPLAY 0.659574 (-6065 2660);
PAINT MONO (-6065 2660);
DISPLAY INVISIBLE (-6065 2660);
FORCEPROP 1 LASTPIN (-6075 2650) BN 10
J 0
(-6087 2658);
DISPLAY 0.489362 (-6087 2658);
PAINT GREEN (-6087 2658);
FORCEPROP 2 LAST CDS_LIB mstr_standard
J 0
(-6025 2650);
DISPLAY 0.723404 (-6025 2650);
PAINT MONO (-6025 2650);
DISPLAY INVISIBLE (-6025 2650);
FORCEPROP 1 LAST BODY_TYPE PLUMBING
J 0
(-6025 2700);
DISPLAY 0.872340 (-6025 2700);
PAINT GREEN (-6025 2700);
DISPLAY INVISIBLE (-6025 2700);
FORCEPROP 1 LAST HDL_TAP TRUE
J 0
(-5700 2525);
DISPLAY 0.872340 (-5700 2525);
DISPLAY INVISIBLE (-5700 2525);
FORCEPROP 1 LAST PATH I45
J 0
(-6027 2650);
DISPLAY 0.872340 (-6027 2650);
PAINT GREEN (-6027 2650);
DISPLAY INVISIBLE (-6027 2650);
FORCEADD TAP..1
(-6025 2700);
FORCEPROP 3 LASTPIN (-6075 2700) SIG_NAME M_H_CPU0_SB_DQ<11>
J 0
(-6065 2710);
DISPLAY 0.659574 (-6065 2710);
PAINT MONO (-6065 2710);
DISPLAY INVISIBLE (-6065 2710);
FORCEPROP 1 LASTPIN (-6075 2700) BN 11
J 0
(-6087 2708);
DISPLAY 0.489362 (-6087 2708);
PAINT GREEN (-6087 2708);
FORCEPROP 2 LAST CDS_LIB mstr_standard
J 0
(-6025 2700);
DISPLAY 0.723404 (-6025 2700);
PAINT MONO (-6025 2700);
DISPLAY INVISIBLE (-6025 2700);
FORCEPROP 1 LAST BODY_TYPE PLUMBING
J 0
(-6025 2750);
DISPLAY 0.872340 (-6025 2750);
PAINT GREEN (-6025 2750);
DISPLAY INVISIBLE (-6025 2750);
FORCEPROP 1 LAST HDL_TAP TRUE
J 0
(-5700 2575);
DISPLAY 0.872340 (-5700 2575);
DISPLAY INVISIBLE (-5700 2575);
FORCEPROP 1 LAST PATH I46
J 0
(-6027 2700);
DISPLAY 0.872340 (-6027 2700);
PAINT GREEN (-6027 2700);
DISPLAY INVISIBLE (-6027 2700);
FORCEADD TAP..1
(-6025 2750);
FORCEPROP 3 LASTPIN (-6075 2750) SIG_NAME M_H_CPU0_SB_DQ<12>
J 0
(-6065 2760);
DISPLAY 0.659574 (-6065 2760);
PAINT MONO (-6065 2760);
DISPLAY INVISIBLE (-6065 2760);
FORCEPROP 1 LASTPIN (-6075 2750) BN 12
J 0
(-6087 2758);
DISPLAY 0.489362 (-6087 2758);
PAINT GREEN (-6087 2758);
FORCEPROP 2 LAST CDS_LIB mstr_standard
J 0
(-6025 2750);
DISPLAY 0.723404 (-6025 2750);
PAINT MONO (-6025 2750);
DISPLAY INVISIBLE (-6025 2750);
FORCEPROP 1 LAST BODY_TYPE PLUMBING
J 0
(-6025 2800);
DISPLAY 0.872340 (-6025 2800);
PAINT GREEN (-6025 2800);
DISPLAY INVISIBLE (-6025 2800);
FORCEPROP 1 LAST HDL_TAP TRUE
J 0
(-5700 2625);
DISPLAY 0.872340 (-5700 2625);
DISPLAY INVISIBLE (-5700 2625);
FORCEPROP 1 LAST PATH I47
J 0
(-6027 2750);
DISPLAY 0.872340 (-6027 2750);
PAINT GREEN (-6027 2750);
DISPLAY INVISIBLE (-6027 2750);
FORCEADD TAP..1
(-6025 2800);
FORCEPROP 3 LASTPIN (-6075 2800) SIG_NAME M_H_CPU0_SB_DQ<13>
J 0
(-6065 2810);
DISPLAY 0.659574 (-6065 2810);
PAINT MONO (-6065 2810);
DISPLAY INVISIBLE (-6065 2810);
FORCEPROP 1 LASTPIN (-6075 2800) BN 13
J 0
(-6087 2808);
DISPLAY 0.489362 (-6087 2808);
PAINT GREEN (-6087 2808);
FORCEPROP 2 LAST CDS_LIB mstr_standard
J 0
(-6025 2800);
DISPLAY 0.723404 (-6025 2800);
PAINT MONO (-6025 2800);
DISPLAY INVISIBLE (-6025 2800);
FORCEPROP 1 LAST BODY_TYPE PLUMBING
J 0
(-6025 2850);
DISPLAY 0.872340 (-6025 2850);
PAINT GREEN (-6025 2850);
DISPLAY INVISIBLE (-6025 2850);
FORCEPROP 1 LAST HDL_TAP TRUE
J 0
(-5700 2675);
DISPLAY 0.872340 (-5700 2675);
DISPLAY INVISIBLE (-5700 2675);
FORCEPROP 1 LAST PATH I48
J 0
(-6027 2800);
DISPLAY 0.872340 (-6027 2800);
PAINT GREEN (-6027 2800);
DISPLAY INVISIBLE (-6027 2800);
FORCEADD TAP..1
(-6025 2850);
FORCEPROP 3 LASTPIN (-6075 2850) SIG_NAME M_H_CPU0_SB_DQ<14>
J 0
(-6065 2860);
DISPLAY 0.659574 (-6065 2860);
PAINT MONO (-6065 2860);
DISPLAY INVISIBLE (-6065 2860);
FORCEPROP 1 LASTPIN (-6075 2850) BN 14
J 0
(-6087 2858);
DISPLAY 0.489362 (-6087 2858);
PAINT GREEN (-6087 2858);
FORCEPROP 2 LAST CDS_LIB mstr_standard
J 0
(-6025 2850);
DISPLAY 0.723404 (-6025 2850);
PAINT MONO (-6025 2850);
DISPLAY INVISIBLE (-6025 2850);
FORCEPROP 1 LAST BODY_TYPE PLUMBING
J 0
(-6025 2900);
DISPLAY 0.872340 (-6025 2900);
PAINT GREEN (-6025 2900);
DISPLAY INVISIBLE (-6025 2900);
FORCEPROP 1 LAST HDL_TAP TRUE
J 0
(-5700 2725);
DISPLAY 0.872340 (-5700 2725);
DISPLAY INVISIBLE (-5700 2725);
FORCEPROP 1 LAST PATH I49
J 0
(-6027 2850);
DISPLAY 0.872340 (-6027 2850);
PAINT GREEN (-6027 2850);
DISPLAY INVISIBLE (-6027 2850);
FORCEADD VCC_CORE..1
(-8550 3375);
FORCEPROP 3 LASTPIN (-8550 3325) SIG_NAME P3V3_STBY\g
J 0
(-8540 3335);
DISPLAY 0.659574 (-8540 3335);
PAINT MONO (-8540 3335);
DISPLAY INVISIBLE (-8540 3335);
FORCEPROP 1 LAST HDL_POWER P3V3_STBY
J 1
(-8550 3425);
DISPLAY 0.489362 (-8550 3425);
PAINT GREEN (-8550 3425);
FORCEPROP 2 LAST CDS_LIB mstr_symbols
J 0
(-8550 3375);
PAINT MONO (-8550 3375);
DISPLAY INVISIBLE (-8550 3375);
FORCEPROP 1 LAST PATH I5
J 0
(-8500 3400);
DISPLAY 0.872340 (-8500 3400);
PAINT AQUA (-8500 3400);
DISPLAY INVISIBLE (-8500 3400);
FORCEPROP 0 LAST VOLTAGE 3.3
J 0
(-8825 3525);
DISPLAY 1.021277 (-8825 3525);
PAINT SKYBLUE (-8825 3525);
DISPLAY INVISIBLE (-8825 3525);
FORCEPROP 2 LAST ROOM PVCCINFAON_CPU0_CTRL
J 0
(-8550 3475);
DISPLAY 0.808511 (-8550 3475);
PAINT RED (-8550 3475);
DISPLAY INVISIBLE (-8550 3475);
FORCEADD TAP..1
(-6025 2950);
FORCEPROP 3 LASTPIN (-6075 2950) SIG_NAME M_H_CPU0_SB_DQ<16>
J 0
(-6065 2960);
DISPLAY 0.659574 (-6065 2960);
PAINT MONO (-6065 2960);
DISPLAY INVISIBLE (-6065 2960);
FORCEPROP 1 LASTPIN (-6075 2950) BN 16
J 0
(-6087 2958);
DISPLAY 0.489362 (-6087 2958);
PAINT GREEN (-6087 2958);
FORCEPROP 2 LAST CDS_LIB mstr_standard
J 0
(-6025 2950);
DISPLAY 0.723404 (-6025 2950);
PAINT MONO (-6025 2950);
DISPLAY INVISIBLE (-6025 2950);
FORCEPROP 1 LAST BODY_TYPE PLUMBING
J 0
(-6025 3000);
DISPLAY 0.872340 (-6025 3000);
PAINT GREEN (-6025 3000);
DISPLAY INVISIBLE (-6025 3000);
FORCEPROP 1 LAST HDL_TAP TRUE
J 0
(-5700 2825);
DISPLAY 0.872340 (-5700 2825);
DISPLAY INVISIBLE (-5700 2825);
FORCEPROP 1 LAST PATH I50
J 0
(-6027 2950);
DISPLAY 0.872340 (-6027 2950);
PAINT GREEN (-6027 2950);
DISPLAY INVISIBLE (-6027 2950);
FORCEADD TAP..1
(-6025 2900);
FORCEPROP 3 LASTPIN (-6075 2900) SIG_NAME M_H_CPU0_SB_DQ<15>
J 0
(-6065 2910);
DISPLAY 0.659574 (-6065 2910);
PAINT MONO (-6065 2910);
DISPLAY INVISIBLE (-6065 2910);
FORCEPROP 1 LASTPIN (-6075 2900) BN 15
J 0
(-6087 2908);
DISPLAY 0.489362 (-6087 2908);
PAINT GREEN (-6087 2908);
FORCEPROP 2 LAST CDS_LIB mstr_standard
J 0
(-6025 2900);
DISPLAY 0.723404 (-6025 2900);
PAINT MONO (-6025 2900);
DISPLAY INVISIBLE (-6025 2900);
FORCEPROP 1 LAST BODY_TYPE PLUMBING
J 0
(-6025 2950);
DISPLAY 0.872340 (-6025 2950);
PAINT GREEN (-6025 2950);
DISPLAY INVISIBLE (-6025 2950);
FORCEPROP 1 LAST HDL_TAP TRUE
J 0
(-5700 2775);
DISPLAY 0.872340 (-5700 2775);
DISPLAY INVISIBLE (-5700 2775);
FORCEPROP 1 LAST PATH I51
J 0
(-6027 2900);
DISPLAY 0.872340 (-6027 2900);
PAINT GREEN (-6027 2900);
DISPLAY INVISIBLE (-6027 2900);
FORCEADD TAP..1
(-6025 3000);
FORCEPROP 3 LASTPIN (-6075 3000) SIG_NAME M_H_CPU0_SB_DQ<17>
J 0
(-6065 3010);
DISPLAY 0.659574 (-6065 3010);
PAINT MONO (-6065 3010);
DISPLAY INVISIBLE (-6065 3010);
FORCEPROP 1 LASTPIN (-6075 3000) BN 17
J 0
(-6087 3008);
DISPLAY 0.489362 (-6087 3008);
PAINT GREEN (-6087 3008);
FORCEPROP 2 LAST CDS_LIB mstr_standard
J 0
(-6025 3000);
DISPLAY 0.723404 (-6025 3000);
PAINT MONO (-6025 3000);
DISPLAY INVISIBLE (-6025 3000);
FORCEPROP 1 LAST BODY_TYPE PLUMBING
J 0
(-6025 3050);
DISPLAY 0.872340 (-6025 3050);
PAINT GREEN (-6025 3050);
DISPLAY INVISIBLE (-6025 3050);
FORCEPROP 1 LAST HDL_TAP TRUE
J 0
(-5700 2875);
DISPLAY 0.872340 (-5700 2875);
DISPLAY INVISIBLE (-5700 2875);
FORCEPROP 1 LAST PATH I52
J 0
(-6027 3000);
DISPLAY 0.872340 (-6027 3000);
PAINT GREEN (-6027 3000);
DISPLAY INVISIBLE (-6027 3000);
FORCEADD TAP..1
(-6025 3100);
FORCEPROP 3 LASTPIN (-6075 3100) SIG_NAME M_H_CPU0_SB_DQ<19>
J 0
(-6065 3110);
DISPLAY 0.659574 (-6065 3110);
PAINT MONO (-6065 3110);
DISPLAY INVISIBLE (-6065 3110);
FORCEPROP 1 LASTPIN (-6075 3100) BN 19
J 0
(-6087 3108);
DISPLAY 0.489362 (-6087 3108);
PAINT GREEN (-6087 3108);
FORCEPROP 2 LAST CDS_LIB mstr_standard
J 0
(-6025 3100);
DISPLAY 0.723404 (-6025 3100);
PAINT MONO (-6025 3100);
DISPLAY INVISIBLE (-6025 3100);
FORCEPROP 1 LAST BODY_TYPE PLUMBING
J 0
(-6025 3150);
DISPLAY 0.872340 (-6025 3150);
PAINT GREEN (-6025 3150);
DISPLAY INVISIBLE (-6025 3150);
FORCEPROP 1 LAST HDL_TAP TRUE
J 0
(-5700 2975);
DISPLAY 0.872340 (-5700 2975);
DISPLAY INVISIBLE (-5700 2975);
FORCEPROP 1 LAST PATH I53
J 0
(-6027 3100);
DISPLAY 0.872340 (-6027 3100);
PAINT GREEN (-6027 3100);
DISPLAY INVISIBLE (-6027 3100);
FORCEADD TAP..1
(-6025 3150);
FORCEPROP 3 LASTPIN (-6075 3150) SIG_NAME M_H_CPU0_SB_DQ<20>
J 0
(-6065 3160);
DISPLAY 0.659574 (-6065 3160);
PAINT MONO (-6065 3160);
DISPLAY INVISIBLE (-6065 3160);
FORCEPROP 1 LASTPIN (-6075 3150) BN 20
J 0
(-6087 3158);
DISPLAY 0.489362 (-6087 3158);
PAINT GREEN (-6087 3158);
FORCEPROP 2 LAST CDS_LIB mstr_standard
J 0
(-6025 3150);
DISPLAY 0.723404 (-6025 3150);
PAINT MONO (-6025 3150);
DISPLAY INVISIBLE (-6025 3150);
FORCEPROP 1 LAST BODY_TYPE PLUMBING
J 0
(-6025 3200);
DISPLAY 0.872340 (-6025 3200);
PAINT GREEN (-6025 3200);
DISPLAY INVISIBLE (-6025 3200);
FORCEPROP 1 LAST HDL_TAP TRUE
J 0
(-5700 3025);
DISPLAY 0.872340 (-5700 3025);
DISPLAY INVISIBLE (-5700 3025);
FORCEPROP 1 LAST PATH I54
J 0
(-6027 3150);
DISPLAY 0.872340 (-6027 3150);
PAINT GREEN (-6027 3150);
DISPLAY INVISIBLE (-6027 3150);
FORCEADD TAP..1
(-6025 3250);
FORCEPROP 3 LASTPIN (-6075 3250) SIG_NAME M_H_CPU0_SB_DQ<22>
J 0
(-6065 3260);
DISPLAY 0.659574 (-6065 3260);
PAINT MONO (-6065 3260);
DISPLAY INVISIBLE (-6065 3260);
FORCEPROP 1 LASTPIN (-6075 3250) BN 22
J 0
(-6087 3258);
DISPLAY 0.489362 (-6087 3258);
PAINT GREEN (-6087 3258);
FORCEPROP 2 LAST CDS_LIB mstr_standard
J 0
(-6025 3250);
DISPLAY 0.723404 (-6025 3250);
PAINT MONO (-6025 3250);
DISPLAY INVISIBLE (-6025 3250);
FORCEPROP 1 LAST BODY_TYPE PLUMBING
J 0
(-6025 3300);
DISPLAY 0.872340 (-6025 3300);
PAINT GREEN (-6025 3300);
DISPLAY INVISIBLE (-6025 3300);
FORCEPROP 1 LAST HDL_TAP TRUE
J 0
(-5700 3125);
DISPLAY 0.872340 (-5700 3125);
DISPLAY INVISIBLE (-5700 3125);
FORCEPROP 1 LAST PATH I55
J 0
(-6027 3250);
DISPLAY 0.872340 (-6027 3250);
PAINT GREEN (-6027 3250);
DISPLAY INVISIBLE (-6027 3250);
FORCEADD TAP..1
(-6025 3200);
FORCEPROP 3 LASTPIN (-6075 3200) SIG_NAME M_H_CPU0_SB_DQ<21>
J 0
(-6065 3210);
DISPLAY 0.659574 (-6065 3210);
PAINT MONO (-6065 3210);
DISPLAY INVISIBLE (-6065 3210);
FORCEPROP 1 LASTPIN (-6075 3200) BN 21
J 0
(-6087 3208);
DISPLAY 0.489362 (-6087 3208);
PAINT GREEN (-6087 3208);
FORCEPROP 2 LAST CDS_LIB mstr_standard
J 0
(-6025 3200);
DISPLAY 0.723404 (-6025 3200);
PAINT MONO (-6025 3200);
DISPLAY INVISIBLE (-6025 3200);
FORCEPROP 1 LAST BODY_TYPE PLUMBING
J 0
(-6025 3250);
DISPLAY 0.872340 (-6025 3250);
PAINT GREEN (-6025 3250);
DISPLAY INVISIBLE (-6025 3250);
FORCEPROP 1 LAST HDL_TAP TRUE
J 0
(-5700 3075);
DISPLAY 0.872340 (-5700 3075);
DISPLAY INVISIBLE (-5700 3075);
FORCEPROP 1 LAST PATH I56
J 0
(-6027 3200);
DISPLAY 0.872340 (-6027 3200);
PAINT GREEN (-6027 3200);
DISPLAY INVISIBLE (-6027 3200);
FORCEADD TAP..1
(-6025 3050);
FORCEPROP 3 LASTPIN (-6075 3050) SIG_NAME M_H_CPU0_SB_DQ<18>
J 0
(-6065 3060);
DISPLAY 0.659574 (-6065 3060);
PAINT MONO (-6065 3060);
DISPLAY INVISIBLE (-6065 3060);
FORCEPROP 1 LASTPIN (-6075 3050) BN 18
J 0
(-6087 3058);
DISPLAY 0.489362 (-6087 3058);
PAINT GREEN (-6087 3058);
FORCEPROP 2 LAST CDS_LIB mstr_standard
J 0
(-6025 3050);
DISPLAY 0.723404 (-6025 3050);
PAINT MONO (-6025 3050);
DISPLAY INVISIBLE (-6025 3050);
FORCEPROP 1 LAST BODY_TYPE PLUMBING
J 0
(-6025 3100);
DISPLAY 0.872340 (-6025 3100);
PAINT GREEN (-6025 3100);
DISPLAY INVISIBLE (-6025 3100);
FORCEPROP 1 LAST HDL_TAP TRUE
J 0
(-5700 2925);
DISPLAY 0.872340 (-5700 2925);
DISPLAY INVISIBLE (-5700 2925);
FORCEPROP 1 LAST PATH I57
J 0
(-6027 3050);
DISPLAY 0.872340 (-6027 3050);
PAINT GREEN (-6027 3050);
DISPLAY INVISIBLE (-6027 3050);
FORCEADD TAP..1
(-6025 3350);
FORCEPROP 3 LASTPIN (-6075 3350) SIG_NAME M_H_CPU0_SB_DQ<24>
J 0
(-6065 3360);
DISPLAY 0.659574 (-6065 3360);
PAINT MONO (-6065 3360);
DISPLAY INVISIBLE (-6065 3360);
FORCEPROP 1 LASTPIN (-6075 3350) BN 24
J 0
(-6087 3358);
DISPLAY 0.489362 (-6087 3358);
PAINT GREEN (-6087 3358);
FORCEPROP 2 LAST CDS_LIB mstr_standard
J 0
(-6025 3350);
DISPLAY 0.723404 (-6025 3350);
PAINT MONO (-6025 3350);
DISPLAY INVISIBLE (-6025 3350);
FORCEPROP 1 LAST BODY_TYPE PLUMBING
J 0
(-6025 3400);
DISPLAY 0.872340 (-6025 3400);
PAINT GREEN (-6025 3400);
DISPLAY INVISIBLE (-6025 3400);
FORCEPROP 1 LAST HDL_TAP TRUE
J 0
(-5700 3225);
DISPLAY 0.872340 (-5700 3225);
DISPLAY INVISIBLE (-5700 3225);
FORCEPROP 1 LAST PATH I58
J 0
(-6027 3350);
DISPLAY 0.872340 (-6027 3350);
PAINT GREEN (-6027 3350);
DISPLAY INVISIBLE (-6027 3350);
FORCEADD TAP..1
(-6025 3400);
FORCEPROP 3 LASTPIN (-6075 3400) SIG_NAME M_H_CPU0_SB_DQ<25>
J 0
(-6065 3410);
DISPLAY 0.659574 (-6065 3410);
PAINT MONO (-6065 3410);
DISPLAY INVISIBLE (-6065 3410);
FORCEPROP 1 LASTPIN (-6075 3400) BN 25
J 0
(-6087 3408);
DISPLAY 0.489362 (-6087 3408);
PAINT GREEN (-6087 3408);
FORCEPROP 2 LAST CDS_LIB mstr_standard
J 0
(-6025 3400);
DISPLAY 0.723404 (-6025 3400);
PAINT MONO (-6025 3400);
DISPLAY INVISIBLE (-6025 3400);
FORCEPROP 1 LAST BODY_TYPE PLUMBING
J 0
(-6025 3450);
DISPLAY 0.872340 (-6025 3450);
PAINT GREEN (-6025 3450);
DISPLAY INVISIBLE (-6025 3450);
FORCEPROP 1 LAST HDL_TAP TRUE
J 0
(-5700 3275);
DISPLAY 0.872340 (-5700 3275);
DISPLAY INVISIBLE (-5700 3275);
FORCEPROP 1 LAST PATH I59
J 0
(-6027 3400);
DISPLAY 0.872340 (-6027 3400);
PAINT GREEN (-6027 3400);
DISPLAY INVISIBLE (-6027 3400);
FORCEADD TAP..1
(-6025 3500);
FORCEPROP 3 LASTPIN (-6075 3500) SIG_NAME M_H_CPU0_SB_DQ<27>
J 0
(-6065 3510);
DISPLAY 0.659574 (-6065 3510);
PAINT MONO (-6065 3510);
DISPLAY INVISIBLE (-6065 3510);
FORCEPROP 1 LASTPIN (-6075 3500) BN 27
J 0
(-6087 3508);
DISPLAY 0.489362 (-6087 3508);
PAINT GREEN (-6087 3508);
FORCEPROP 2 LAST CDS_LIB mstr_standard
J 0
(-6025 3500);
DISPLAY 0.723404 (-6025 3500);
PAINT MONO (-6025 3500);
DISPLAY INVISIBLE (-6025 3500);
FORCEPROP 1 LAST BODY_TYPE PLUMBING
J 0
(-6025 3550);
DISPLAY 0.872340 (-6025 3550);
PAINT GREEN (-6025 3550);
DISPLAY INVISIBLE (-6025 3550);
FORCEPROP 1 LAST HDL_TAP TRUE
J 0
(-5700 3375);
DISPLAY 0.872340 (-5700 3375);
DISPLAY INVISIBLE (-5700 3375);
FORCEPROP 1 LAST PATH I60
J 0
(-6027 3500);
DISPLAY 0.872340 (-6027 3500);
PAINT GREEN (-6027 3500);
DISPLAY INVISIBLE (-6027 3500);
FORCEADD TAP..1
(-6025 3450);
FORCEPROP 3 LASTPIN (-6075 3450) SIG_NAME M_H_CPU0_SB_DQ<26>
J 0
(-6065 3460);
DISPLAY 0.659574 (-6065 3460);
PAINT MONO (-6065 3460);
DISPLAY INVISIBLE (-6065 3460);
FORCEPROP 1 LASTPIN (-6075 3450) BN 26
J 0
(-6087 3458);
DISPLAY 0.489362 (-6087 3458);
PAINT GREEN (-6087 3458);
FORCEPROP 2 LAST CDS_LIB mstr_standard
J 0
(-6025 3450);
DISPLAY 0.723404 (-6025 3450);
PAINT MONO (-6025 3450);
DISPLAY INVISIBLE (-6025 3450);
FORCEPROP 1 LAST BODY_TYPE PLUMBING
J 0
(-6025 3500);
DISPLAY 0.872340 (-6025 3500);
PAINT GREEN (-6025 3500);
DISPLAY INVISIBLE (-6025 3500);
FORCEPROP 1 LAST HDL_TAP TRUE
J 0
(-5700 3325);
DISPLAY 0.872340 (-5700 3325);
DISPLAY INVISIBLE (-5700 3325);
FORCEPROP 1 LAST PATH I61
J 0
(-6027 3450);
DISPLAY 0.872340 (-6027 3450);
PAINT GREEN (-6027 3450);
DISPLAY INVISIBLE (-6027 3450);
FORCEADD TAP..1
(-6025 3300);
FORCEPROP 3 LASTPIN (-6075 3300) SIG_NAME M_H_CPU0_SB_DQ<23>
J 0
(-6065 3310);
DISPLAY 0.659574 (-6065 3310);
PAINT MONO (-6065 3310);
DISPLAY INVISIBLE (-6065 3310);
FORCEPROP 1 LASTPIN (-6075 3300) BN 23
J 0
(-6087 3308);
DISPLAY 0.489362 (-6087 3308);
PAINT GREEN (-6087 3308);
FORCEPROP 2 LAST CDS_LIB mstr_standard
J 0
(-6025 3300);
DISPLAY 0.723404 (-6025 3300);
PAINT MONO (-6025 3300);
DISPLAY INVISIBLE (-6025 3300);
FORCEPROP 1 LAST BODY_TYPE PLUMBING
J 0
(-6025 3350);
DISPLAY 0.872340 (-6025 3350);
PAINT GREEN (-6025 3350);
DISPLAY INVISIBLE (-6025 3350);
FORCEPROP 1 LAST HDL_TAP TRUE
J 0
(-5700 3175);
DISPLAY 0.872340 (-5700 3175);
DISPLAY INVISIBLE (-5700 3175);
FORCEPROP 1 LAST PATH I62
J 0
(-6027 3300);
DISPLAY 0.872340 (-6027 3300);
PAINT GREEN (-6027 3300);
DISPLAY INVISIBLE (-6027 3300);
FORCEADD TAP..1
(-6025 3600);
FORCEPROP 3 LASTPIN (-6075 3600) SIG_NAME M_H_CPU0_SB_DQ<29>
J 0
(-6065 3610);
DISPLAY 0.659574 (-6065 3610);
PAINT MONO (-6065 3610);
DISPLAY INVISIBLE (-6065 3610);
FORCEPROP 1 LASTPIN (-6075 3600) BN 29
J 0
(-6087 3608);
DISPLAY 0.489362 (-6087 3608);
PAINT GREEN (-6087 3608);
FORCEPROP 2 LAST CDS_LIB mstr_standard
J 0
(-6025 3600);
DISPLAY 0.723404 (-6025 3600);
PAINT MONO (-6025 3600);
DISPLAY INVISIBLE (-6025 3600);
FORCEPROP 1 LAST BODY_TYPE PLUMBING
J 0
(-6025 3650);
DISPLAY 0.872340 (-6025 3650);
PAINT GREEN (-6025 3650);
DISPLAY INVISIBLE (-6025 3650);
FORCEPROP 1 LAST HDL_TAP TRUE
J 0
(-5700 3475);
DISPLAY 0.872340 (-5700 3475);
DISPLAY INVISIBLE (-5700 3475);
FORCEPROP 1 LAST PATH I63
J 0
(-6027 3600);
DISPLAY 0.872340 (-6027 3600);
PAINT GREEN (-6027 3600);
DISPLAY INVISIBLE (-6027 3600);
FORCEADD TAP..1
(-6025 3700);
FORCEPROP 3 LASTPIN (-6075 3700) SIG_NAME M_H_CPU0_SB_DQ<31>
J 0
(-6065 3710);
DISPLAY 0.659574 (-6065 3710);
PAINT MONO (-6065 3710);
DISPLAY INVISIBLE (-6065 3710);
FORCEPROP 1 LASTPIN (-6075 3700) BN 31
J 0
(-6087 3708);
DISPLAY 0.489362 (-6087 3708);
PAINT GREEN (-6087 3708);
FORCEPROP 2 LAST CDS_LIB mstr_standard
J 0
(-6025 3700);
DISPLAY 0.723404 (-6025 3700);
PAINT MONO (-6025 3700);
DISPLAY INVISIBLE (-6025 3700);
FORCEPROP 1 LAST BODY_TYPE PLUMBING
J 0
(-6025 3750);
DISPLAY 0.872340 (-6025 3750);
PAINT GREEN (-6025 3750);
DISPLAY INVISIBLE (-6025 3750);
FORCEPROP 1 LAST HDL_TAP TRUE
J 0
(-5700 3575);
DISPLAY 0.872340 (-5700 3575);
DISPLAY INVISIBLE (-5700 3575);
FORCEPROP 1 LAST PATH I64
J 0
(-6027 3700);
DISPLAY 0.872340 (-6027 3700);
PAINT GREEN (-6027 3700);
DISPLAY INVISIBLE (-6027 3700);
FORCEADD TAP..1
(-6025 3650);
FORCEPROP 3 LASTPIN (-6075 3650) SIG_NAME M_H_CPU0_SB_DQ<30>
J 0
(-6065 3660);
DISPLAY 0.659574 (-6065 3660);
PAINT MONO (-6065 3660);
DISPLAY INVISIBLE (-6065 3660);
FORCEPROP 1 LASTPIN (-6075 3650) BN 30
J 0
(-6087 3658);
DISPLAY 0.489362 (-6087 3658);
PAINT GREEN (-6087 3658);
FORCEPROP 2 LAST CDS_LIB mstr_standard
J 0
(-6025 3650);
DISPLAY 0.723404 (-6025 3650);
PAINT MONO (-6025 3650);
DISPLAY INVISIBLE (-6025 3650);
FORCEPROP 1 LAST BODY_TYPE PLUMBING
J 0
(-6025 3700);
DISPLAY 0.872340 (-6025 3700);
PAINT GREEN (-6025 3700);
DISPLAY INVISIBLE (-6025 3700);
FORCEPROP 1 LAST HDL_TAP TRUE
J 0
(-5700 3525);
DISPLAY 0.872340 (-5700 3525);
DISPLAY INVISIBLE (-5700 3525);
FORCEPROP 1 LAST PATH I65
J 0
(-6027 3650);
DISPLAY 0.872340 (-6027 3650);
PAINT GREEN (-6027 3650);
DISPLAY INVISIBLE (-6027 3650);
FORCEADD TAP..1
(-6025 3550);
FORCEPROP 3 LASTPIN (-6075 3550) SIG_NAME M_H_CPU0_SB_DQ<28>
J 0
(-6065 3560);
DISPLAY 0.659574 (-6065 3560);
PAINT MONO (-6065 3560);
DISPLAY INVISIBLE (-6065 3560);
FORCEPROP 1 LASTPIN (-6075 3550) BN 28
J 0
(-6087 3558);
DISPLAY 0.489362 (-6087 3558);
PAINT GREEN (-6087 3558);
FORCEPROP 2 LAST CDS_LIB mstr_standard
J 0
(-6025 3550);
DISPLAY 0.723404 (-6025 3550);
PAINT MONO (-6025 3550);
DISPLAY INVISIBLE (-6025 3550);
FORCEPROP 1 LAST BODY_TYPE PLUMBING
J 0
(-6025 3600);
DISPLAY 0.872340 (-6025 3600);
PAINT GREEN (-6025 3600);
DISPLAY INVISIBLE (-6025 3600);
FORCEPROP 1 LAST HDL_TAP TRUE
J 0
(-5700 3425);
DISPLAY 0.872340 (-5700 3425);
DISPLAY INVISIBLE (-5700 3425);
FORCEPROP 1 LAST PATH I66
J 0
(-6027 3550);
DISPLAY 0.872340 (-6027 3550);
PAINT GREEN (-6027 3550);
DISPLAY INVISIBLE (-6027 3550);
FORCEADD OFFPAGE..3
(-5350 3750);
FORCEPROP 2 LAST $XR0 17 
J 0
(-5136 3750);
DISPLAY 0.638298 (-5136 3750);
PAINT MONO (-5136 3750);
FORCEPROP 2 LAST PATH I73
J 0
(-5150 3825);
DISPLAY 1.021277 (-5150 3825);
DISPLAY INVISIBLE (-5150 3825);
FORCEPROP 1 LAST COMMENT_BODY TRUE
J 0
(-5400 3650);
DISPLAY 0.872340 (-5400 3650);
PAINT GREEN (-5400 3650);
DISPLAY INVISIBLE (-5400 3650);
FORCEPROP 1 LAST OFFPAGE TRUE
J 0
(-5025 3625);
DISPLAY 0.872340 (-5025 3625);
PAINT GREEN (-5025 3625);
DISPLAY INVISIBLE (-5025 3625);
FORCEPROP 2 LAST CDS_LIB mstr_standard
J 0
(-5350 3750);
DISPLAY 0.723404 (-5350 3750);
PAINT MONO (-5350 3750);
DISPLAY INVISIBLE (-5350 3750);
FORCEADD TAP..1
R 2
(-7725 3800);
FORCEPROP 3 LASTPIN (-7675 3800) SIG_NAME M_H_CPU0_SA_CB<4>
J 0
(-7665 3810);
DISPLAY 0.659574 (-7665 3810);
PAINT MONO (-7665 3810);
DISPLAY INVISIBLE (-7665 3810);
FORCEPROP 1 LASTPIN (-7675 3800) BN 4
J 2
(-7663 3808);
DISPLAY 0.489362 (-7663 3808);
PAINT GREEN (-7663 3808);
FORCEPROP 2 LAST CDS_LIB mstr_standard
J 0
(-7725 3800);
DISPLAY 0.723404 (-7725 3800);
PAINT MONO (-7725 3800);
DISPLAY INVISIBLE (-7725 3800);
FORCEPROP 1 LAST BODY_TYPE PLUMBING
J 2
(-7725 3850);
DISPLAY 0.872340 (-7725 3850);
PAINT GREEN (-7725 3850);
DISPLAY INVISIBLE (-7725 3850);
FORCEPROP 1 LAST HDL_TAP TRUE
J 2
(-8050 3675);
DISPLAY 0.872340 (-8050 3675);
DISPLAY INVISIBLE (-8050 3675);
FORCEPROP 1 LAST PATH I76
J 2
(-7723 3800);
DISPLAY 0.872340 (-7723 3800);
PAINT GREEN (-7723 3800);
DISPLAY INVISIBLE (-7723 3800);
FORCEADD TAP..1
R 2
(-7725 3850);
FORCEPROP 3 LASTPIN (-7675 3850) SIG_NAME M_H_CPU0_SA_CB<5>
J 0
(-7665 3860);
DISPLAY 0.659574 (-7665 3860);
PAINT MONO (-7665 3860);
DISPLAY INVISIBLE (-7665 3860);
FORCEPROP 1 LASTPIN (-7675 3850) BN 5
J 2
(-7663 3858);
DISPLAY 0.489362 (-7663 3858);
PAINT GREEN (-7663 3858);
FORCEPROP 2 LAST CDS_LIB mstr_standard
J 0
(-7725 3850);
DISPLAY 0.723404 (-7725 3850);
PAINT MONO (-7725 3850);
DISPLAY INVISIBLE (-7725 3850);
FORCEPROP 1 LAST BODY_TYPE PLUMBING
J 2
(-7725 3900);
DISPLAY 0.872340 (-7725 3900);
PAINT GREEN (-7725 3900);
DISPLAY INVISIBLE (-7725 3900);
FORCEPROP 1 LAST HDL_TAP TRUE
J 2
(-8050 3725);
DISPLAY 0.872340 (-8050 3725);
DISPLAY INVISIBLE (-8050 3725);
FORCEPROP 1 LAST PATH I77
J 2
(-7723 3850);
DISPLAY 0.872340 (-7723 3850);
PAINT GREEN (-7723 3850);
DISPLAY INVISIBLE (-7723 3850);
FORCEADD TAP..1
R 2
(-7725 3950);
FORCEPROP 3 LASTPIN (-7675 3950) SIG_NAME M_H_CPU0_SA_CB<7>
J 0
(-7665 3960);
DISPLAY 0.659574 (-7665 3960);
PAINT MONO (-7665 3960);
DISPLAY INVISIBLE (-7665 3960);
FORCEPROP 1 LASTPIN (-7675 3950) BN 7
J 2
(-7663 3958);
DISPLAY 0.489362 (-7663 3958);
PAINT GREEN (-7663 3958);
FORCEPROP 2 LAST CDS_LIB mstr_standard
J 0
(-7725 3950);
DISPLAY 0.723404 (-7725 3950);
PAINT MONO (-7725 3950);
DISPLAY INVISIBLE (-7725 3950);
FORCEPROP 1 LAST BODY_TYPE PLUMBING
J 2
(-7725 4000);
DISPLAY 0.872340 (-7725 4000);
PAINT GREEN (-7725 4000);
DISPLAY INVISIBLE (-7725 4000);
FORCEPROP 1 LAST HDL_TAP TRUE
J 2
(-8050 3825);
DISPLAY 0.872340 (-8050 3825);
DISPLAY INVISIBLE (-8050 3825);
FORCEPROP 1 LAST PATH I78
J 2
(-7723 3950);
DISPLAY 0.872340 (-7723 3950);
PAINT GREEN (-7723 3950);
DISPLAY INVISIBLE (-7723 3950);
FORCEADD TAP..1
R 2
(-7725 3900);
FORCEPROP 3 LASTPIN (-7675 3900) SIG_NAME M_H_CPU0_SA_CB<6>
J 0
(-7665 3910);
DISPLAY 0.659574 (-7665 3910);
PAINT MONO (-7665 3910);
DISPLAY INVISIBLE (-7665 3910);
FORCEPROP 1 LASTPIN (-7675 3900) BN 6
J 2
(-7663 3908);
DISPLAY 0.489362 (-7663 3908);
PAINT GREEN (-7663 3908);
FORCEPROP 2 LAST CDS_LIB mstr_standard
J 0
(-7725 3900);
DISPLAY 0.723404 (-7725 3900);
PAINT MONO (-7725 3900);
DISPLAY INVISIBLE (-7725 3900);
FORCEPROP 1 LAST BODY_TYPE PLUMBING
J 2
(-7725 3950);
DISPLAY 0.872340 (-7725 3950);
PAINT GREEN (-7725 3950);
DISPLAY INVISIBLE (-7725 3950);
FORCEPROP 1 LAST HDL_TAP TRUE
J 2
(-8050 3775);
DISPLAY 0.872340 (-8050 3775);
DISPLAY INVISIBLE (-8050 3775);
FORCEPROP 1 LAST PATH I79
J 2
(-7723 3900);
DISPLAY 0.872340 (-7723 3900);
PAINT GREEN (-7723 3900);
DISPLAY INVISIBLE (-7723 3900);
FORCEADD OFFPAGE..1
(-8325 2850);
FORCEPROP 2 LAST $XR0 92 
J 0
(-8546 2850);
DISPLAY 0.638298 (-8546 2850);
PAINT MONO (-8546 2850);
FORCEPROP 2 LAST PATH I8
J 0
(-8575 2900);
DISPLAY 1.021277 (-8575 2900);
DISPLAY INVISIBLE (-8575 2900);
FORCEPROP 1 LAST COMMENT_BODY TRUE
J 0
(-8200 2750);
DISPLAY 0.872340 (-8200 2750);
PAINT GREEN (-8200 2750);
DISPLAY INVISIBLE (-8200 2750);
FORCEPROP 1 LAST OFFPAGE TRUE
J 0
(-8000 2725);
DISPLAY 0.872340 (-8000 2725);
PAINT GREEN (-8000 2725);
DISPLAY INVISIBLE (-8000 2725);
FORCEPROP 2 LAST CDS_LIB mstr_standard
J 0
(-8325 2850);
DISPLAY 0.808511 (-8325 2850);
DISPLAY INVISIBLE (-8325 2850);
FORCEADD TAP..1
R 2
(-7725 4650);
FORCEPROP 3 LASTPIN (-7675 4650) SIG_NAME M_H_CPU0_SB_CA<0>
J 0
(-7665 4660);
DISPLAY 0.659574 (-7665 4660);
PAINT MONO (-7665 4660);
DISPLAY INVISIBLE (-7665 4660);
FORCEPROP 1 LASTPIN (-7675 4650) BN 0
J 2
(-7663 4658);
DISPLAY 0.489362 (-7663 4658);
PAINT GREEN (-7663 4658);
FORCEPROP 2 LAST CDS_LIB mstr_standard
J 0
(-7725 4650);
DISPLAY 0.723404 (-7725 4650);
PAINT MONO (-7725 4650);
DISPLAY INVISIBLE (-7725 4650);
FORCEPROP 1 LAST BODY_TYPE PLUMBING
J 2
(-7725 4700);
DISPLAY 0.872340 (-7725 4700);
PAINT GREEN (-7725 4700);
DISPLAY INVISIBLE (-7725 4700);
FORCEPROP 1 LAST HDL_TAP TRUE
J 2
(-8050 4525);
DISPLAY 0.872340 (-8050 4525);
DISPLAY INVISIBLE (-8050 4525);
FORCEPROP 1 LAST PATH I80
J 2
(-7723 4650);
DISPLAY 0.872340 (-7723 4650);
PAINT GREEN (-7723 4650);
DISPLAY INVISIBLE (-7723 4650);
FORCEADD TAP..1
R 2
(-7725 4700);
FORCEPROP 3 LASTPIN (-7675 4700) SIG_NAME M_H_CPU0_SB_CA<1>
J 0
(-7665 4710);
DISPLAY 0.659574 (-7665 4710);
PAINT MONO (-7665 4710);
DISPLAY INVISIBLE (-7665 4710);
FORCEPROP 1 LASTPIN (-7675 4700) BN 1
J 2
(-7663 4708);
DISPLAY 0.489362 (-7663 4708);
PAINT GREEN (-7663 4708);
FORCEPROP 2 LAST CDS_LIB mstr_standard
J 0
(-7725 4700);
DISPLAY 0.723404 (-7725 4700);
PAINT MONO (-7725 4700);
DISPLAY INVISIBLE (-7725 4700);
FORCEPROP 1 LAST BODY_TYPE PLUMBING
J 2
(-7725 4750);
DISPLAY 0.872340 (-7725 4750);
PAINT GREEN (-7725 4750);
DISPLAY INVISIBLE (-7725 4750);
FORCEPROP 1 LAST HDL_TAP TRUE
J 2
(-8050 4575);
DISPLAY 0.872340 (-8050 4575);
DISPLAY INVISIBLE (-8050 4575);
FORCEPROP 1 LAST PATH I81
J 2
(-7723 4700);
DISPLAY 0.872340 (-7723 4700);
PAINT GREEN (-7723 4700);
DISPLAY INVISIBLE (-7723 4700);
FORCEADD TAP..1
R 2
(-7725 4750);
FORCEPROP 3 LASTPIN (-7675 4750) SIG_NAME M_H_CPU0_SB_CA<2>
J 0
(-7665 4760);
DISPLAY 0.659574 (-7665 4760);
PAINT MONO (-7665 4760);
DISPLAY INVISIBLE (-7665 4760);
FORCEPROP 1 LASTPIN (-7675 4750) BN 2
J 2
(-7663 4758);
DISPLAY 0.489362 (-7663 4758);
PAINT GREEN (-7663 4758);
FORCEPROP 2 LAST CDS_LIB mstr_standard
J 0
(-7725 4750);
DISPLAY 0.723404 (-7725 4750);
PAINT MONO (-7725 4750);
DISPLAY INVISIBLE (-7725 4750);
FORCEPROP 1 LAST BODY_TYPE PLUMBING
J 2
(-7725 4800);
DISPLAY 0.872340 (-7725 4800);
PAINT GREEN (-7725 4800);
DISPLAY INVISIBLE (-7725 4800);
FORCEPROP 1 LAST HDL_TAP TRUE
J 2
(-8050 4625);
DISPLAY 0.872340 (-8050 4625);
DISPLAY INVISIBLE (-8050 4625);
FORCEPROP 1 LAST PATH I82
J 2
(-7723 4750);
DISPLAY 0.872340 (-7723 4750);
PAINT GREEN (-7723 4750);
DISPLAY INVISIBLE (-7723 4750);
FORCEADD TAP..1
R 2
(-7725 4850);
FORCEPROP 3 LASTPIN (-7675 4850) SIG_NAME M_H_CPU0_SB_CA<4>
J 0
(-7665 4860);
DISPLAY 0.659574 (-7665 4860);
PAINT MONO (-7665 4860);
DISPLAY INVISIBLE (-7665 4860);
FORCEPROP 1 LASTPIN (-7675 4850) BN 4
J 2
(-7663 4858);
DISPLAY 0.489362 (-7663 4858);
PAINT GREEN (-7663 4858);
FORCEPROP 2 LAST CDS_LIB mstr_standard
J 0
(-7725 4850);
DISPLAY 0.723404 (-7725 4850);
PAINT MONO (-7725 4850);
DISPLAY INVISIBLE (-7725 4850);
FORCEPROP 1 LAST BODY_TYPE PLUMBING
J 2
(-7725 4900);
DISPLAY 0.872340 (-7725 4900);
PAINT GREEN (-7725 4900);
DISPLAY INVISIBLE (-7725 4900);
FORCEPROP 1 LAST HDL_TAP TRUE
J 2
(-8050 4725);
DISPLAY 0.872340 (-8050 4725);
DISPLAY INVISIBLE (-8050 4725);
FORCEPROP 1 LAST PATH I83
J 2
(-7723 4850);
DISPLAY 0.872340 (-7723 4850);
PAINT GREEN (-7723 4850);
DISPLAY INVISIBLE (-7723 4850);
FORCEADD TAP..1
R 2
(-7725 4800);
FORCEPROP 3 LASTPIN (-7675 4800) SIG_NAME M_H_CPU0_SB_CA<3>
J 0
(-7665 4810);
DISPLAY 0.659574 (-7665 4810);
PAINT MONO (-7665 4810);
DISPLAY INVISIBLE (-7665 4810);
FORCEPROP 1 LASTPIN (-7675 4800) BN 3
J 2
(-7663 4808);
DISPLAY 0.489362 (-7663 4808);
PAINT GREEN (-7663 4808);
FORCEPROP 2 LAST CDS_LIB mstr_standard
J 0
(-7725 4800);
DISPLAY 0.723404 (-7725 4800);
PAINT MONO (-7725 4800);
DISPLAY INVISIBLE (-7725 4800);
FORCEPROP 1 LAST BODY_TYPE PLUMBING
J 2
(-7725 4850);
DISPLAY 0.872340 (-7725 4850);
PAINT GREEN (-7725 4850);
DISPLAY INVISIBLE (-7725 4850);
FORCEPROP 1 LAST HDL_TAP TRUE
J 2
(-8050 4675);
DISPLAY 0.872340 (-8050 4675);
DISPLAY INVISIBLE (-8050 4675);
FORCEPROP 1 LAST PATH I84
J 2
(-7723 4800);
DISPLAY 0.872340 (-7723 4800);
PAINT GREEN (-7723 4800);
DISPLAY INVISIBLE (-7723 4800);
FORCEADD TAP..1
R 2
(-7725 4900);
FORCEPROP 3 LASTPIN (-7675 4900) SIG_NAME M_H_CPU0_SB_CA<5>
J 0
(-7665 4910);
DISPLAY 0.659574 (-7665 4910);
PAINT MONO (-7665 4910);
DISPLAY INVISIBLE (-7665 4910);
FORCEPROP 1 LASTPIN (-7675 4900) BN 5
J 2
(-7663 4908);
DISPLAY 0.489362 (-7663 4908);
PAINT GREEN (-7663 4908);
FORCEPROP 2 LAST CDS_LIB mstr_standard
J 0
(-7725 4900);
DISPLAY 0.723404 (-7725 4900);
PAINT MONO (-7725 4900);
DISPLAY INVISIBLE (-7725 4900);
FORCEPROP 1 LAST BODY_TYPE PLUMBING
J 2
(-7725 4950);
DISPLAY 0.872340 (-7725 4950);
PAINT GREEN (-7725 4950);
DISPLAY INVISIBLE (-7725 4950);
FORCEPROP 1 LAST HDL_TAP TRUE
J 2
(-8050 4775);
DISPLAY 0.872340 (-8050 4775);
DISPLAY INVISIBLE (-8050 4775);
FORCEPROP 1 LAST PATH I85
J 2
(-7723 4900);
DISPLAY 0.872340 (-7723 4900);
PAINT GREEN (-7723 4900);
DISPLAY INVISIBLE (-7723 4900);
FORCEADD TAP..1
R 2
(-7725 4950);
FORCEPROP 3 LASTPIN (-7675 4950) SIG_NAME M_H_CPU0_SB_CA<6>
J 0
(-7665 4960);
DISPLAY 0.659574 (-7665 4960);
PAINT MONO (-7665 4960);
DISPLAY INVISIBLE (-7665 4960);
FORCEPROP 1 LASTPIN (-7675 4950) BN 6
J 2
(-7663 4958);
DISPLAY 0.489362 (-7663 4958);
PAINT GREEN (-7663 4958);
FORCEPROP 2 LAST CDS_LIB mstr_standard
J 0
(-7725 4950);
DISPLAY 0.723404 (-7725 4950);
PAINT MONO (-7725 4950);
DISPLAY INVISIBLE (-7725 4950);
FORCEPROP 1 LAST BODY_TYPE PLUMBING
J 2
(-7725 5000);
DISPLAY 0.872340 (-7725 5000);
PAINT GREEN (-7725 5000);
DISPLAY INVISIBLE (-7725 5000);
FORCEPROP 1 LAST HDL_TAP TRUE
J 2
(-8050 4825);
DISPLAY 0.872340 (-8050 4825);
DISPLAY INVISIBLE (-8050 4825);
FORCEPROP 1 LAST PATH I86
J 2
(-7723 4950);
DISPLAY 0.872340 (-7723 4950);
PAINT GREEN (-7723 4950);
DISPLAY INVISIBLE (-7723 4950);
FORCEADD TAP..1
R 2
(-7725 5050);
FORCEPROP 3 LASTPIN (-7675 5050) SIG_NAME M_H_CPU0_SA_CA<0>
J 0
(-7665 5060);
DISPLAY 0.659574 (-7665 5060);
PAINT MONO (-7665 5060);
DISPLAY INVISIBLE (-7665 5060);
FORCEPROP 1 LASTPIN (-7675 5050) BN 0
J 2
(-7663 5058);
DISPLAY 0.489362 (-7663 5058);
PAINT GREEN (-7663 5058);
FORCEPROP 2 LAST CDS_LIB mstr_standard
J 0
(-7725 5050);
DISPLAY 0.723404 (-7725 5050);
PAINT MONO (-7725 5050);
DISPLAY INVISIBLE (-7725 5050);
FORCEPROP 1 LAST BODY_TYPE PLUMBING
J 2
(-7725 5100);
DISPLAY 0.872340 (-7725 5100);
PAINT GREEN (-7725 5100);
DISPLAY INVISIBLE (-7725 5100);
FORCEPROP 1 LAST HDL_TAP TRUE
J 2
(-8050 4925);
DISPLAY 0.872340 (-8050 4925);
DISPLAY INVISIBLE (-8050 4925);
FORCEPROP 1 LAST PATH I87
J 2
(-7723 5050);
DISPLAY 0.872340 (-7723 5050);
PAINT GREEN (-7723 5050);
DISPLAY INVISIBLE (-7723 5050);
FORCEADD TAP..1
R 2
(-7725 5100);
FORCEPROP 3 LASTPIN (-7675 5100) SIG_NAME M_H_CPU0_SA_CA<1>
J 0
(-7665 5110);
DISPLAY 0.659574 (-7665 5110);
PAINT MONO (-7665 5110);
DISPLAY INVISIBLE (-7665 5110);
FORCEPROP 1 LASTPIN (-7675 5100) BN 1
J 2
(-7663 5108);
DISPLAY 0.489362 (-7663 5108);
PAINT GREEN (-7663 5108);
FORCEPROP 2 LAST CDS_LIB mstr_standard
J 0
(-7725 5100);
DISPLAY 0.723404 (-7725 5100);
PAINT MONO (-7725 5100);
DISPLAY INVISIBLE (-7725 5100);
FORCEPROP 1 LAST BODY_TYPE PLUMBING
J 2
(-7725 5150);
DISPLAY 0.872340 (-7725 5150);
PAINT GREEN (-7725 5150);
DISPLAY INVISIBLE (-7725 5150);
FORCEPROP 1 LAST HDL_TAP TRUE
J 2
(-8050 4975);
DISPLAY 0.872340 (-8050 4975);
DISPLAY INVISIBLE (-8050 4975);
FORCEPROP 1 LAST PATH I88
J 2
(-7723 5100);
DISPLAY 0.872340 (-7723 5100);
PAINT GREEN (-7723 5100);
DISPLAY INVISIBLE (-7723 5100);
FORCEADD TAP..1
R 2
(-7725 5150);
FORCEPROP 3 LASTPIN (-7675 5150) SIG_NAME M_H_CPU0_SA_CA<2>
J 0
(-7665 5160);
DISPLAY 0.659574 (-7665 5160);
PAINT MONO (-7665 5160);
DISPLAY INVISIBLE (-7665 5160);
FORCEPROP 1 LASTPIN (-7675 5150) BN 2
J 2
(-7663 5158);
DISPLAY 0.489362 (-7663 5158);
PAINT GREEN (-7663 5158);
FORCEPROP 2 LAST CDS_LIB mstr_standard
J 0
(-7725 5150);
DISPLAY 0.723404 (-7725 5150);
PAINT MONO (-7725 5150);
DISPLAY INVISIBLE (-7725 5150);
FORCEPROP 1 LAST BODY_TYPE PLUMBING
J 2
(-7725 5200);
DISPLAY 0.872340 (-7725 5200);
PAINT GREEN (-7725 5200);
DISPLAY INVISIBLE (-7725 5200);
FORCEPROP 1 LAST HDL_TAP TRUE
J 2
(-8050 5025);
DISPLAY 0.872340 (-8050 5025);
DISPLAY INVISIBLE (-8050 5025);
FORCEPROP 1 LAST PATH I89
J 2
(-7723 5150);
DISPLAY 0.872340 (-7723 5150);
PAINT GREEN (-7723 5150);
DISPLAY INVISIBLE (-7723 5150);
FORCEADD OFFPAGE..1
(-8175 3050);
FORCEPROP 2 LAST $XR0 17 
J 0
(-8396 3050);
DISPLAY 0.638298 (-8396 3050);
PAINT MONO (-8396 3050);
FORCEPROP 2 LAST PATH I9
J 0
(-8600 3100);
DISPLAY 1.021277 (-8600 3100);
DISPLAY INVISIBLE (-8600 3100);
FORCEPROP 1 LAST COMMENT_BODY TRUE
J 0
(-8050 2950);
DISPLAY 0.872340 (-8050 2950);
PAINT GREEN (-8050 2950);
DISPLAY INVISIBLE (-8050 2950);
FORCEPROP 1 LAST OFFPAGE TRUE
J 0
(-7850 2925);
DISPLAY 0.872340 (-7850 2925);
PAINT GREEN (-7850 2925);
DISPLAY INVISIBLE (-7850 2925);
FORCEPROP 2 LAST CDS_LIB mstr_standard
J 0
(-8175 3050);
DISPLAY 0.808511 (-8175 3050);
DISPLAY INVISIBLE (-8175 3050);
FORCEADD TAP..1
R 2
(-7725 5200);
FORCEPROP 3 LASTPIN (-7675 5200) SIG_NAME M_H_CPU0_SA_CA<3>
J 0
(-7665 5210);
DISPLAY 0.659574 (-7665 5210);
PAINT MONO (-7665 5210);
DISPLAY INVISIBLE (-7665 5210);
FORCEPROP 1 LASTPIN (-7675 5200) BN 3
J 2
(-7663 5208);
DISPLAY 0.489362 (-7663 5208);
PAINT GREEN (-7663 5208);
FORCEPROP 2 LAST CDS_LIB mstr_standard
J 0
(-7725 5200);
DISPLAY 0.723404 (-7725 5200);
PAINT MONO (-7725 5200);
DISPLAY INVISIBLE (-7725 5200);
FORCEPROP 1 LAST BODY_TYPE PLUMBING
J 2
(-7725 5250);
DISPLAY 0.872340 (-7725 5250);
PAINT GREEN (-7725 5250);
DISPLAY INVISIBLE (-7725 5250);
FORCEPROP 1 LAST HDL_TAP TRUE
J 2
(-8050 5075);
DISPLAY 0.872340 (-8050 5075);
DISPLAY INVISIBLE (-8050 5075);
FORCEPROP 1 LAST PATH I90
J 2
(-7723 5200);
DISPLAY 0.872340 (-7723 5200);
PAINT GREEN (-7723 5200);
DISPLAY INVISIBLE (-7723 5200);
FORCEADD TAP..1
R 2
(-7725 5250);
FORCEPROP 3 LASTPIN (-7675 5250) SIG_NAME M_H_CPU0_SA_CA<4>
J 0
(-7665 5260);
DISPLAY 0.659574 (-7665 5260);
PAINT MONO (-7665 5260);
DISPLAY INVISIBLE (-7665 5260);
FORCEPROP 1 LASTPIN (-7675 5250) BN 4
J 2
(-7663 5258);
DISPLAY 0.489362 (-7663 5258);
PAINT GREEN (-7663 5258);
FORCEPROP 2 LAST CDS_LIB mstr_standard
J 0
(-7725 5250);
DISPLAY 0.723404 (-7725 5250);
PAINT MONO (-7725 5250);
DISPLAY INVISIBLE (-7725 5250);
FORCEPROP 1 LAST BODY_TYPE PLUMBING
J 2
(-7725 5300);
DISPLAY 0.872340 (-7725 5300);
PAINT GREEN (-7725 5300);
DISPLAY INVISIBLE (-7725 5300);
FORCEPROP 1 LAST HDL_TAP TRUE
J 2
(-8050 5125);
DISPLAY 0.872340 (-8050 5125);
DISPLAY INVISIBLE (-8050 5125);
FORCEPROP 1 LAST PATH I91
J 2
(-7723 5250);
DISPLAY 0.872340 (-7723 5250);
PAINT GREEN (-7723 5250);
DISPLAY INVISIBLE (-7723 5250);
FORCEADD TAP..1
R 2
(-7725 5300);
FORCEPROP 3 LASTPIN (-7675 5300) SIG_NAME M_H_CPU0_SA_CA<5>
J 0
(-7665 5310);
DISPLAY 0.659574 (-7665 5310);
PAINT MONO (-7665 5310);
DISPLAY INVISIBLE (-7665 5310);
FORCEPROP 1 LASTPIN (-7675 5300) BN 5
J 2
(-7663 5308);
DISPLAY 0.489362 (-7663 5308);
PAINT GREEN (-7663 5308);
FORCEPROP 2 LAST CDS_LIB mstr_standard
J 0
(-7725 5300);
DISPLAY 0.723404 (-7725 5300);
PAINT MONO (-7725 5300);
DISPLAY INVISIBLE (-7725 5300);
FORCEPROP 1 LAST BODY_TYPE PLUMBING
J 2
(-7725 5350);
DISPLAY 0.872340 (-7725 5350);
PAINT GREEN (-7725 5350);
DISPLAY INVISIBLE (-7725 5350);
FORCEPROP 1 LAST HDL_TAP TRUE
J 2
(-8050 5175);
DISPLAY 0.872340 (-8050 5175);
DISPLAY INVISIBLE (-8050 5175);
FORCEPROP 1 LAST PATH I92
J 2
(-7723 5300);
DISPLAY 0.872340 (-7723 5300);
PAINT GREEN (-7723 5300);
DISPLAY INVISIBLE (-7723 5300);
FORCEADD TAP..1
R 2
(-7725 5350);
FORCEPROP 3 LASTPIN (-7675 5350) SIG_NAME M_H_CPU0_SA_CA<6>
J 0
(-7665 5360);
DISPLAY 0.659574 (-7665 5360);
PAINT MONO (-7665 5360);
DISPLAY INVISIBLE (-7665 5360);
FORCEPROP 1 LASTPIN (-7675 5350) BN 6
J 2
(-7663 5358);
DISPLAY 0.489362 (-7663 5358);
PAINT GREEN (-7663 5358);
FORCEPROP 2 LAST CDS_LIB mstr_standard
J 0
(-7725 5350);
DISPLAY 0.723404 (-7725 5350);
PAINT MONO (-7725 5350);
DISPLAY INVISIBLE (-7725 5350);
FORCEPROP 1 LAST BODY_TYPE PLUMBING
J 2
(-7725 5400);
DISPLAY 0.872340 (-7725 5400);
PAINT GREEN (-7725 5400);
DISPLAY INVISIBLE (-7725 5400);
FORCEPROP 1 LAST HDL_TAP TRUE
J 2
(-8050 5225);
DISPLAY 0.872340 (-8050 5225);
DISPLAY INVISIBLE (-8050 5225);
FORCEPROP 1 LAST PATH I93
J 2
(-7723 5350);
DISPLAY 0.872340 (-7723 5350);
PAINT GREEN (-7723 5350);
DISPLAY INVISIBLE (-7723 5350);
FORCEADD TAP..1
(-6025 3800);
FORCEPROP 3 LASTPIN (-6075 3800) SIG_NAME M_H_CPU0_SA_DQ<0>
J 0
(-6065 3810);
DISPLAY 0.659574 (-6065 3810);
PAINT MONO (-6065 3810);
DISPLAY INVISIBLE (-6065 3810);
FORCEPROP 1 LASTPIN (-6075 3800) BN 0
J 0
(-6087 3808);
DISPLAY 0.489362 (-6087 3808);
PAINT GREEN (-6087 3808);
FORCEPROP 2 LAST CDS_LIB mstr_standard
J 0
(-6025 3800);
DISPLAY 0.723404 (-6025 3800);
PAINT MONO (-6025 3800);
DISPLAY INVISIBLE (-6025 3800);
FORCEPROP 1 LAST BODY_TYPE PLUMBING
J 0
(-6025 3850);
DISPLAY 0.872340 (-6025 3850);
PAINT GREEN (-6025 3850);
DISPLAY INVISIBLE (-6025 3850);
FORCEPROP 1 LAST HDL_TAP TRUE
J 0
(-5700 3675);
DISPLAY 0.872340 (-5700 3675);
DISPLAY INVISIBLE (-5700 3675);
FORCEPROP 1 LAST PATH I94
J 0
(-6027 3800);
DISPLAY 0.872340 (-6027 3800);
PAINT GREEN (-6027 3800);
DISPLAY INVISIBLE (-6027 3800);
FORCEADD TAP..1
(-6025 3850);
FORCEPROP 3 LASTPIN (-6075 3850) SIG_NAME M_H_CPU0_SA_DQ<1>
J 0
(-6065 3860);
DISPLAY 0.659574 (-6065 3860);
PAINT MONO (-6065 3860);
DISPLAY INVISIBLE (-6065 3860);
FORCEPROP 1 LASTPIN (-6075 3850) BN 1
J 0
(-6087 3858);
DISPLAY 0.489362 (-6087 3858);
PAINT GREEN (-6087 3858);
FORCEPROP 2 LAST CDS_LIB mstr_standard
J 0
(-6025 3850);
DISPLAY 0.723404 (-6025 3850);
PAINT MONO (-6025 3850);
DISPLAY INVISIBLE (-6025 3850);
FORCEPROP 1 LAST BODY_TYPE PLUMBING
J 0
(-6025 3900);
DISPLAY 0.872340 (-6025 3900);
PAINT GREEN (-6025 3900);
DISPLAY INVISIBLE (-6025 3900);
FORCEPROP 1 LAST HDL_TAP TRUE
J 0
(-5700 3725);
DISPLAY 0.872340 (-5700 3725);
DISPLAY INVISIBLE (-5700 3725);
FORCEPROP 1 LAST PATH I95
J 0
(-6027 3850);
DISPLAY 0.872340 (-6027 3850);
PAINT GREEN (-6027 3850);
DISPLAY INVISIBLE (-6027 3850);
FORCEADD TAP..1
(-6025 3900);
FORCEPROP 3 LASTPIN (-6075 3900) SIG_NAME M_H_CPU0_SA_DQ<2>
J 0
(-6065 3910);
DISPLAY 0.659574 (-6065 3910);
PAINT MONO (-6065 3910);
DISPLAY INVISIBLE (-6065 3910);
FORCEPROP 1 LASTPIN (-6075 3900) BN 2
J 0
(-6087 3908);
DISPLAY 0.489362 (-6087 3908);
PAINT GREEN (-6087 3908);
FORCEPROP 2 LAST CDS_LIB mstr_standard
J 0
(-6025 3900);
DISPLAY 0.723404 (-6025 3900);
PAINT MONO (-6025 3900);
DISPLAY INVISIBLE (-6025 3900);
FORCEPROP 1 LAST BODY_TYPE PLUMBING
J 0
(-6025 3950);
DISPLAY 0.872340 (-6025 3950);
PAINT GREEN (-6025 3950);
DISPLAY INVISIBLE (-6025 3950);
FORCEPROP 1 LAST HDL_TAP TRUE
J 0
(-5700 3775);
DISPLAY 0.872340 (-5700 3775);
DISPLAY INVISIBLE (-5700 3775);
FORCEPROP 1 LAST PATH I96
J 0
(-6027 3900);
DISPLAY 0.872340 (-6027 3900);
PAINT GREEN (-6027 3900);
DISPLAY INVISIBLE (-6027 3900);
FORCEADD TAP..1
(-6025 3950);
FORCEPROP 3 LASTPIN (-6075 3950) SIG_NAME M_H_CPU0_SA_DQ<3>
J 0
(-6065 3960);
DISPLAY 0.659574 (-6065 3960);
PAINT MONO (-6065 3960);
DISPLAY INVISIBLE (-6065 3960);
FORCEPROP 1 LASTPIN (-6075 3950) BN 3
J 0
(-6087 3958);
DISPLAY 0.489362 (-6087 3958);
PAINT GREEN (-6087 3958);
FORCEPROP 2 LAST CDS_LIB mstr_standard
J 0
(-6025 3950);
DISPLAY 0.723404 (-6025 3950);
PAINT MONO (-6025 3950);
DISPLAY INVISIBLE (-6025 3950);
FORCEPROP 1 LAST BODY_TYPE PLUMBING
J 0
(-6025 4000);
DISPLAY 0.872340 (-6025 4000);
PAINT GREEN (-6025 4000);
DISPLAY INVISIBLE (-6025 4000);
FORCEPROP 1 LAST HDL_TAP TRUE
J 0
(-5700 3825);
DISPLAY 0.872340 (-5700 3825);
DISPLAY INVISIBLE (-5700 3825);
FORCEPROP 1 LAST PATH I97
J 0
(-6027 3950);
DISPLAY 0.872340 (-6027 3950);
PAINT GREEN (-6027 3950);
DISPLAY INVISIBLE (-6027 3950);
FORCEADD TAP..1
(-6025 4000);
FORCEPROP 3 LASTPIN (-6075 4000) SIG_NAME M_H_CPU0_SA_DQ<4>
J 0
(-6065 4010);
DISPLAY 0.659574 (-6065 4010);
PAINT MONO (-6065 4010);
DISPLAY INVISIBLE (-6065 4010);
FORCEPROP 1 LASTPIN (-6075 4000) BN 4
J 0
(-6087 4008);
DISPLAY 0.489362 (-6087 4008);
PAINT GREEN (-6087 4008);
FORCEPROP 2 LAST CDS_LIB mstr_standard
J 0
(-6025 4000);
DISPLAY 0.723404 (-6025 4000);
PAINT MONO (-6025 4000);
DISPLAY INVISIBLE (-6025 4000);
FORCEPROP 1 LAST BODY_TYPE PLUMBING
J 0
(-6025 4050);
DISPLAY 0.872340 (-6025 4050);
PAINT GREEN (-6025 4050);
DISPLAY INVISIBLE (-6025 4050);
FORCEPROP 1 LAST HDL_TAP TRUE
J 0
(-5700 3875);
DISPLAY 0.872340 (-5700 3875);
DISPLAY INVISIBLE (-5700 3875);
FORCEPROP 1 LAST PATH I98
J 0
(-6027 4000);
DISPLAY 0.872340 (-6027 4000);
PAINT GREEN (-6027 4000);
DISPLAY INVISIBLE (-6027 4000);
FORCEADD TAP..1
(-6025 4050);
FORCEPROP 3 LASTPIN (-6075 4050) SIG_NAME M_H_CPU0_SA_DQ<5>
J 0
(-6065 4060);
DISPLAY 0.659574 (-6065 4060);
PAINT MONO (-6065 4060);
DISPLAY INVISIBLE (-6065 4060);
FORCEPROP 1 LASTPIN (-6075 4050) BN 5
J 0
(-6087 4058);
DISPLAY 0.489362 (-6087 4058);
PAINT GREEN (-6087 4058);
FORCEPROP 2 LAST CDS_LIB mstr_standard
J 0
(-6025 4050);
DISPLAY 0.723404 (-6025 4050);
PAINT MONO (-6025 4050);
DISPLAY INVISIBLE (-6025 4050);
FORCEPROP 1 LAST BODY_TYPE PLUMBING
J 0
(-6025 4100);
DISPLAY 0.872340 (-6025 4100);
PAINT GREEN (-6025 4100);
DISPLAY INVISIBLE (-6025 4100);
FORCEPROP 1 LAST HDL_TAP TRUE
J 0
(-5700 3925);
DISPLAY 0.872340 (-5700 3925);
DISPLAY INVISIBLE (-5700 3925);
FORCEPROP 1 LAST PATH I99
J 0
(-6027 4050);
DISPLAY 0.872340 (-6027 4050);
PAINT GREEN (-6027 4050);
DISPLAY INVISIBLE (-6027 4050);
FORCEADD QUANTA_TITLE_BLOCK_C..1
(0 0);
FORCEPROP 0 LAST CDS_CON_LAST_MODIFIED Fri Mar 11 14:52:57 2022
J 0
(-1885 15);
DISPLAY INVISIBLE (-1885 15);
FORCEPROP 1 LAST CUSTOM_TXT_CDS <CON_LAST_MODIFIED>
J 0
(-1885 15);
DISPLAY 0.978723 (-1885 15);
FORCEPROP 2 LAST CUSTOM_TXT_CDS <XR_PAGE_TITLE>
J 0
(-7890 5250);
DISPLAY 0.638298 (-7890 5250);
PAINT PINK (-7890 5250);
DISPLAY INVISIBLE (-7890 5250);
FORCEPROP 1 LAST CUSTOM_TXT_CDS <NAME_2>
J 0
(-3175 50);
FORCEPROP 1 LAST CUSTOM_TXT_CDS <NAME_1>
J 0
(-3175 175);
FORCEPROP 1 LAST CUSTOM_TXT_CDS <Q_NUMBER>
J 0
(-1403 103);
DISPLAY 1.212766 (-1403 103);
FORCEPROP 1 LAST CUSTOM_TXT_CDS <Q_PROJ>
J 0
(-2382 102);
DISPLAY 1.212766 (-2382 102);
FORCEPROP 1 LAST CUSTOM_TXT_CDS <Q_REV>
J 0
(-184 103);
DISPLAY 1.212766 (-184 103);
FORCEPROP 1 LAST CUSTOM_TXT_CDS <CON_PAGE_NUM> OF <CON_TOTAL_PAGES>
J 0
(-446 18);
DISPLAY 0.978723 (-446 18);
FORCEPROP 1 LAST Q_TITLE DDR5 - CPU0 CHH
J 0
(-9275 75);
DISPLAY 2.446809 (-9275 75);
PAINT GREEN (-9275 75);
FORCEPROP 1 LAST Q_DEPT BU9
J 1
(-3763 49);
DISPLAY 1.957447 (-3763 49);
PAINT GREEN (-3763 49);
FORCEPROP 2 LAST PAGE_BORDER TRUE
J 0
(-7890 5250);
DISPLAY 0.638298 (-7890 5250);
PAINT PINK (-7890 5250);
DISPLAY INVISIBLE (-7890 5250);
FORCEPROP 1 LAST CDS_LMAN_SYM_OUTLINE -9475,6775,100,-125
J 0
(0 0);
DISPLAY 0.468085 (0 0);
PAINT GREEN (0 0);
DISPLAY INVISIBLE (0 0);
FORCEPROP 2 LAST CDS_LIB pure_quanta
J 0
(0 0);
DISPLAY INVISIBLE (0 0);
FORCEPROP 1 LAST COMMENT_BODY TRUE
J 0
(12 -13);
DISPLAY 0.978723 (12 -13);
PAINT GREEN (12 -13);
DISPLAY INVISIBLE (12 -13);
FORCEPROP 2 LAST CDS_XR_PAGE_TITLE CR-92 : @T6G_MB_LIB.T6G(SCH_1):PAGE92
J 0
(-7890 5250);
DISPLAY 0.638298 (-7890 5250);
PAINT PINK (-7890 5250);
DISPLAY INVISIBLE (-7890 5250);
FORCEADD DNS..2
(-8375 2250);
PAINT RED (-8375 2250);
FORCEPROP 2 LAST CDS_LIB mstr_misc
J 0
(-8375 2250);
DISPLAY INVISIBLE (-8375 2250);
FORCEPROP 1 LAST COMMENT_BODY TRUE
R 1
J 0
(-8300 2025);
DISPLAY 0.872340 (-8300 2025);
PAINT PEACH (-8300 2025);
DISPLAY INVISIBLE (-8300 2025);
WIRE 17 -1 (-7775 3975)(-7775 3925);
WIRE 17 -1 (-7775 3975)(-7775 4000);
WIRE 17 -1 (-7775 3875)(-7775 3925);
WIRE 17 -1 (-7775 3875)(-7775 3825);
WIRE 17 -1 (-7775 4000)(-8275 4000);
FORCEPROP 2 LAST SIG_NAME M_H_CPU0_SA_CB<7:0>
J 0
(-8225 4010);
DISPLAY 0.489362 (-8225 4010);
WIRE 17 -1 (-7775 3775)(-7775 3825);
WIRE 17 -1 (-7775 3725)(-7775 3775);
WIRE 17 -1 (-7775 3675)(-7775 3725);
WIRE 17 -1 (-7775 3625)(-7775 3675);
WIRE 17 -1 (-7775 3525)(-7775 3550);
WIRE 17 -1 (-7775 3525)(-7775 3475);
WIRE 17 -1 (-7775 3550)(-8275 3550);
FORCEPROP 2 LAST SIG_NAME M_H_CPU0_SB_CB<7:0>
J 0
(-8225 3560);
DISPLAY 0.489362 (-8225 3560);
WIRE 17 -1 (-7775 5075)(-7775 5125);
WIRE 17 -1 (-7775 5125)(-7775 5175);
WIRE 17 -1 (-7775 5175)(-7775 5225);
WIRE 17 -1 (-7775 5225)(-7775 5275);
WIRE 17 -1 (-7775 5275)(-7775 5325);
WIRE 17 -1 (-7775 5325)(-7775 5375);
WIRE 17 -1 (-7775 5375)(-7775 5400);
WIRE 17 -1 (-7775 5400)(-8275 5400);
FORCEPROP 2 LAST SIG_NAME M_H_CPU0_SA_CA<6:0>
J 0
(-8260 5410);
DISPLAY 0.489362 (-8260 5410);
WIRE 17 -1 (-7775 4675)(-7775 4725);
WIRE 17 -1 (-7775 4725)(-7775 4775);
WIRE 17 -1 (-7775 4775)(-7775 4825);
WIRE 17 -1 (-7775 4825)(-7775 4875);
WIRE 17 -1 (-7775 4875)(-7775 4925);
WIRE 17 -1 (-7775 4925)(-7775 4975);
WIRE 17 -1 (-7775 4975)(-7775 5000);
WIRE 17 -1 (-7775 5000)(-8275 5000);
FORCEPROP 2 LAST SIG_NAME M_H_CPU0_SB_CA<6:0>
J 0
(-8260 5010);
DISPLAY 0.489362 (-8260 5010);
WIRE 17 -1 (-7775 3425)(-7775 3475);
WIRE 17 -1 (-7775 3425)(-7775 3375);
WIRE 17 -1 (-7775 3325)(-7775 3375);
WIRE 17 -1 (-7775 3275)(-7775 3325);
WIRE 17 -1 (-7775 3225)(-7775 3275);
WIRE 17 -1 (-7775 3175)(-7775 3225);
WIRE 17 -1 (-5975 5375)(-5975 5325);
WIRE 17 -1 (-5975 5400)(-5975 5375);
WIRE 17 -1 (-5975 5325)(-5975 5275);
WIRE 17 -1 (-5975 5275)(-5975 5225);
WIRE 17 -1 (-5975 5400)(-5400 5400);
FORCEPROP 2 LAST SIG_NAME M_H_CPU0_SA_DQ<31:0>
J 0
(-5910 5410);
DISPLAY 0.489362 (-5910 5410);
WIRE 17 -1 (-5975 5225)(-5975 5175);
WIRE 17 -1 (-5975 5175)(-5975 5125);
WIRE 17 -1 (-5975 5125)(-5975 5075);
WIRE 17 -1 (-5975 5075)(-5975 5025);
WIRE 17 -1 (-5975 5025)(-5975 4975);
WIRE 17 -1 (-5975 4975)(-5975 4925);
WIRE 17 -1 (-5975 4925)(-5975 4875);
WIRE 17 -1 (-5975 4875)(-5975 4825);
WIRE 17 -1 (-5975 4825)(-5975 4775);
WIRE 17 -1 (-5975 4775)(-5975 4725);
WIRE 17 -1 (-5975 4725)(-5975 4675);
WIRE 17 -1 (-5975 4675)(-5975 4625);
WIRE 17 -1 (-5975 4575)(-5975 4625);
WIRE 17 -1 (-5975 4525)(-5975 4575);
WIRE 17 -1 (-5975 4475)(-5975 4525);
WIRE 17 -1 (-5975 4425)(-5975 4475);
WIRE 17 -1 (-5975 4425)(-5975 4375);
WIRE 17 -1 (-5975 4375)(-5975 4325);
WIRE 17 -1 (-5975 4325)(-5975 4275);
WIRE 17 -1 (-5975 4275)(-5975 4225);
WIRE 17 -1 (-5975 4225)(-5975 4175);
WIRE 17 -1 (-5975 4175)(-5975 4125);
WIRE 17 -1 (-5975 4125)(-5975 4075);
WIRE 17 -1 (-5975 4075)(-5975 4025);
WIRE 17 -1 (-5975 3975)(-5975 4025);
WIRE 17 -1 (-5975 3925)(-5975 3975);
WIRE 17 -1 (-5975 3875)(-5975 3925);
WIRE 17 -1 (-5975 3825)(-5975 3875);
WIRE 17 -1 (-5975 3750)(-5975 3725);
WIRE 17 -1 (-5975 3750)(-5400 3750);
FORCEPROP 2 LAST SIG_NAME M_H_CPU0_SB_DQ<31:0>
J 0
(-5910 3760);
DISPLAY 0.489362 (-5910 3760);
WIRE 17 -1 (-5975 3675)(-5975 3625);
WIRE 17 -1 (-5975 3725)(-5975 3675);
WIRE 17 -1 (-5975 3625)(-5975 3575);
WIRE 17 -1 (-5975 3575)(-5975 3525);
WIRE 17 -1 (-5975 3525)(-5975 3475);
WIRE 17 -1 (-5975 3475)(-5975 3425);
WIRE 17 -1 (-5975 3425)(-5975 3375);
WIRE 17 -1 (-5975 3375)(-5975 3325);
WIRE 17 -1 (-5975 3325)(-5975 3275);
WIRE 17 -1 (-5975 3275)(-5975 3225);
WIRE 17 -1 (-5975 3225)(-5975 3175);
WIRE 17 -1 (-5975 3175)(-5975 3125);
WIRE 17 -1 (-5975 3125)(-5975 3075);
WIRE 17 -1 (-5975 3075)(-5975 3025);
WIRE 17 -1 (-5975 3025)(-5975 2975);
WIRE 17 -1 (-5975 2925)(-5975 2975);
WIRE 17 -1 (-5975 2875)(-5975 2925);
WIRE 17 -1 (-5975 2825)(-5975 2875);
WIRE 17 -1 (-5975 2775)(-5975 2825);
WIRE 17 -1 (-5975 2775)(-5975 2725);
WIRE 17 -1 (-5975 2725)(-5975 2675);
WIRE 17 -1 (-5975 2675)(-5975 2625);
WIRE 17 -1 (-5975 2625)(-5975 2575);
WIRE 17 -1 (-5975 2575)(-5975 2525);
WIRE 17 -1 (-5975 2525)(-5975 2475);
WIRE 17 -1 (-5975 2475)(-5975 2425);
WIRE 17 -1 (-5975 2425)(-5975 2375);
WIRE 17 -1 (-5975 2325)(-5975 2375);
WIRE 17 -1 (-5975 2275)(-5975 2325);
WIRE 17 -1 (-5975 2225)(-5975 2275);
WIRE 17 -1 (-5975 2175)(-5975 2225);
WIRE 17 -1 (-3250 4125)(-3250 4025);
WIRE 17 -1 (-3250 4225)(-3250 4125);
WIRE 17 -1 (-3250 4025)(-3250 3925);
WIRE 17 -1 (-3250 3825)(-3250 3925);
WIRE 17 -1 (-3250 4325)(-3250 4225);
WIRE 17 -1 (-3250 4350)(-3250 4325);
WIRE 17 -1 (-3250 3725)(-3250 3825);
WIRE 17 -1 (-3250 3625)(-3250 3725);
WIRE 17 -1 (-3250 4350)(-2550 4350);
FORCEPROP 2 LAST SIG_NAME M_H_CPU0_SA_DQS_DN<9:0>
J 0
(-3185 4360);
DISPLAY 0.489362 (-3185 4360);
WIRE 17 -1 (-3450 4075)(-3450 3975);
WIRE 17 -1 (-3450 4175)(-3450 4075);
WIRE 17 -1 (-3450 3875)(-3450 3975);
WIRE 17 -1 (-3450 3775)(-3450 3875);
WIRE 17 -1 (-3450 4275)(-3450 4175);
WIRE 17 -1 (-3450 4375)(-3450 4275);
WIRE 17 -1 (-3450 3675)(-3450 3775);
WIRE 17 -1 (-3450 3675)(-3450 3575);
WIRE 17 -1 (-3450 4400)(-3450 4375);
WIRE 17 -1 (-3450 4400)(-2550 4400);
FORCEPROP 2 LAST SIG_NAME M_H_CPU0_SA_DQS_DP<9:0>
J 0
(-3185 4410);
DISPLAY 0.489362 (-3185 4410);
WIRE 17 -1 (-3450 3225)(-3450 3125);
WIRE 17 -1 (-3450 3325)(-3450 3225);
WIRE 17 -1 (-3450 3125)(-3450 3025);
WIRE 17 -1 (-3450 3025)(-3450 2925);
WIRE 17 -1 (-3450 3350)(-3450 3325);
WIRE 17 -1 (-3450 3350)(-2550 3350);
FORCEPROP 2 LAST SIG_NAME M_H_CPU0_SB_DQS_DP<9:0>
J 0
(-3185 3360);
DISPLAY 0.489362 (-3185 3360);
WIRE 17 -1 (-3250 3175)(-3250 3075);
WIRE 17 -1 (-3250 3275)(-3250 3175);
WIRE 17 -1 (-3250 3075)(-3250 2975);
WIRE 17 -1 (-3250 2975)(-3250 2875);
WIRE 17 -1 (-3250 3300)(-3250 3275);
WIRE 17 -1 (-3250 3300)(-2550 3300);
FORCEPROP 2 LAST SIG_NAME M_H_CPU0_SB_DQS_DN<9:0>
J 0
(-3185 3310);
DISPLAY 0.489362 (-3185 3310);
WIRE 17 -1 (-3450 2825)(-3450 2925);
WIRE 17 -1 (-3450 2725)(-3450 2825);
WIRE 17 -1 (-3450 2625)(-3450 2725);
WIRE 17 -1 (-3250 3525)(-3250 3425);
WIRE 17 -1 (-3250 3625)(-3250 3525);
WIRE 17 -1 (-3450 3575)(-3450 3475);
WIRE 17 -1 (-3250 2475)(-3250 2375);
WIRE 17 -1 (-3250 2575)(-3250 2475);
WIRE 17 -1 (-3250 2575)(-3250 2675);
WIRE 17 -1 (-3250 2675)(-3250 2775);
WIRE 17 -1 (-3250 2775)(-3250 2875);
WIRE 17 -1 (-3450 2525)(-3450 2425);
WIRE 17 -1 (-3450 2625)(-3450 2525);
WIRE 16 -1 (-6425 925)(-6425 1075);
WIRE 16 -1 (-8650 3000)(-8650 3075);
WIRE 16 -1 (-8400 2350)(-8400 2375);
WIRE 16 -1 (-7875 2650)(-8275 2650);
FORCEPROP 2 LAST SIG_NAME I3C_SPD_DDRGL_CPU0_SCL
J 0
(-8335 2660);
DISPLAY 0.489362 (-8335 2660);
WIRE 16 -1 (-7475 2750)(-7575 2750);
FORCEPROP 2 LAST SIG_NAME I3C_SPD_DDRH_CPU0_SCL
J 0
(-7960 2760);
DISPLAY 0.446809 (-7960 2760);
FORCEPROP 2 LASTPROP $XRERR UNIQUE?
J 0
(-8200 2760);
DISPLAY 0.638298 (-8200 2760);
PAINT MONO (-8200 2760);
DISPLAY INVISIBLE (-8200 2760);
WIRE 16 -1 (-7575 2750)(-7575 2650);
WIRE 16 -1 (-7575 2650)(-7675 2650);
WIRE 16 -1 (-7475 2800)(-8275 2800);
FORCEPROP 2 LAST SIG_NAME I3C_SPD_DDRGL_CPU0_SDA
J 0
(-8285 2810);
DISPLAY 0.489362 (-8285 2810);
WIRE 16 -1 (-8400 2150)(-8400 2100);
WIRE 16 -1 (-8200 2100)(-8400 2100);
WIRE 16 -1 (-8400 2100)(-8425 2100);
WIRE 16 -1 (-8200 2500)(-8200 2100);
WIRE 16 -1 (-7475 2500)(-8200 2500);
FORCEPROP 2 LAST SIG_NAME PWRGD_CHH_CPU0_DIMM
J 0
(-8110 2510);
DISPLAY 0.489362 (-8110 2510);
FORCEPROP 2 LASTPROP $XRERR UNIQUE?
J 0
(-8350 2510);
DISPLAY 0.638298 (-8350 2510);
PAINT MONO (-8350 2510);
DISPLAY INVISIBLE (-8350 2510);
WIRE 16 -1 (-7475 2400)(-8100 2400);
FORCEPROP 2 LAST SIG_NAME TP_CHH_CPU0_DIMM_RFU_6
J 0
(-8110 2410);
DISPLAY 0.489362 (-8110 2410);
FORCEPROP 2 LASTPROP $XRERR UNIQUE?
J 0
(-8340 2400);
DISPLAY 0.638298 (-8340 2400);
PAINT MONO (-8340 2400);
DISPLAY INVISIBLE (-8340 2400);
WIRE 16 -1 (-7475 2350)(-8100 2350);
FORCEPROP 2 LAST SIG_NAME TP_CHH_CPU0_DIMM_RFU_5
J 0
(-8110 2360);
DISPLAY 0.489362 (-8110 2360);
FORCEPROP 2 LASTPROP $XRERR UNIQUE?
J 0
(-8340 2350);
DISPLAY 0.638298 (-8340 2350);
PAINT MONO (-8340 2350);
DISPLAY INVISIBLE (-8340 2350);
WIRE 16 -1 (-7475 2850)(-8275 2850);
FORCEPROP 2 LAST SIG_NAME PD_CHH_CPU0_DIMM_SAA
J 0
(-8250 2860);
DISPLAY 0.489362 (-8250 2860);
WIRE 16 -1 (-8550 2900)(-7475 2900);
WIRE 16 -1 (-8550 3300)(-8550 2900);
WIRE 16 -1 (-8550 3325)(-8550 3300);
WIRE 16 -1 (-8650 3300)(-8550 3300);
WIRE 16 -1 (-8650 3275)(-8650 3300);
WIRE 16 -1 (-7475 2200)(-8100 2200);
FORCEPROP 2 LAST SIG_NAME TP_CHH_CPU0_DIMM_RFU_2
J 0
(-8110 2210);
DISPLAY 0.489362 (-8110 2210);
FORCEPROP 2 LASTPROP $XRERR UNIQUE?
J 0
(-8340 2200);
DISPLAY 0.638298 (-8340 2200);
PAINT MONO (-8340 2200);
DISPLAY INVISIBLE (-8340 2200);
WIRE 16 -1 (-7475 2150)(-8100 2150);
FORCEPROP 2 LAST SIG_NAME TP_CHH_CPU0_DIMM_RFU_1
J 0
(-8110 2160);
DISPLAY 0.489362 (-8110 2160);
FORCEPROP 2 LASTPROP $XRERR UNIQUE?
J 0
(-8340 2150);
DISPLAY 0.638298 (-8340 2150);
PAINT MONO (-8340 2150);
DISPLAY INVISIBLE (-8340 2150);
WIRE 16 -1 (-7475 2100)(-8100 2100);
FORCEPROP 2 LAST SIG_NAME TP_CHH_CPU0_DIMM_RFU_0
J 0
(-8110 2110);
DISPLAY 0.489362 (-8110 2110);
FORCEPROP 2 LASTPROP $XRERR UNIQUE?
J 0
(-8340 2100);
DISPLAY 0.638298 (-8340 2100);
PAINT MONO (-8340 2100);
DISPLAY INVISIBLE (-8340 2100);
WIRE 16 -1 (-7475 5350)(-7675 5350);
WIRE 16 -1 (-7475 5300)(-7675 5300);
WIRE 16 -1 (-7475 5250)(-7675 5250);
WIRE 16 -1 (-400 5300)(-400 5250);
WIRE 16 -1 (-400 5300)(-700 5300);
WIRE 16 -1 (-400 5250)(-400 5200);
WIRE 16 -1 (-400 5250)(-700 5250);
WIRE 16 -1 (-400 5200)(-400 5150);
WIRE 16 -1 (-400 5200)(-700 5200);
WIRE 16 -1 (-400 5150)(-700 5150);
WIRE 16 -1 (-400 5150)(-400 5100);
WIRE 16 -1 (-400 5100)(-400 5050);
WIRE 16 -1 (-400 5100)(-700 5100);
WIRE 16 -1 (-400 5050)(-400 5000);
WIRE 16 -1 (-400 5050)(-700 5050);
WIRE 16 -1 (-400 5000)(-400 4950);
WIRE 16 -1 (-400 5000)(-700 5000);
WIRE 16 -1 (-400 4950)(-400 4900);
WIRE 16 -1 (-400 4950)(-700 4950);
WIRE 16 -1 (-400 4900)(-400 4850);
WIRE 16 -1 (-400 4900)(-700 4900);
WIRE 16 -1 (-400 4850)(-400 4800);
WIRE 16 -1 (-400 4850)(-700 4850);
WIRE 16 -1 (-400 4800)(-400 4750);
WIRE 16 -1 (-400 4800)(-700 4800);
WIRE 16 -1 (-400 4750)(-400 4700);
WIRE 16 -1 (-400 4750)(-700 4750);
WIRE 16 -1 (-400 4700)(-400 4650);
WIRE 16 -1 (-400 4700)(-700 4700);
WIRE 16 -1 (-400 4650)(-400 4600);
WIRE 16 -1 (-400 4650)(-700 4650);
WIRE 16 -1 (-400 4600)(-400 4550);
WIRE 16 -1 (-400 4600)(-700 4600);
WIRE 16 -1 (-400 4550)(-400 4500);
WIRE 16 -1 (-400 4550)(-700 4550);
WIRE 16 -1 (-400 4500)(-400 4450);
WIRE 16 -1 (-400 4500)(-700 4500);
WIRE 16 -1 (-400 4450)(-400 4400);
WIRE 16 -1 (-400 4450)(-700 4450);
WIRE 16 -1 (-400 4400)(-400 4350);
WIRE 16 -1 (-400 4400)(-700 4400);
WIRE 16 -1 (-400 4350)(-400 4300);
WIRE 16 -1 (-400 4350)(-700 4350);
WIRE 16 -1 (-400 4300)(-400 4250);
WIRE 16 -1 (-400 4300)(-700 4300);
WIRE 16 -1 (-400 4250)(-400 4200);
WIRE 16 -1 (-400 4250)(-700 4250);
WIRE 16 -1 (-400 4200)(-400 4150);
WIRE 16 -1 (-400 4200)(-700 4200);
WIRE 16 -1 (-400 4150)(-400 4100);
WIRE 16 -1 (-400 4150)(-700 4150);
WIRE 16 -1 (-400 4100)(-700 4100);
WIRE 16 -1 (-400 4100)(-400 4050);
WIRE 16 -1 (-400 4050)(-400 4000);
WIRE 16 -1 (-400 4050)(-700 4050);
WIRE 16 -1 (-400 4000)(-400 3950);
WIRE 16 -1 (-400 4000)(-700 4000);
WIRE 16 -1 (-400 3950)(-400 3900);
WIRE 16 -1 (-400 3950)(-700 3950);
WIRE 16 -1 (-400 3900)(-400 3850);
WIRE 16 -1 (-400 3900)(-700 3900);
WIRE 16 -1 (-400 3850)(-400 3800);
WIRE 16 -1 (-400 3850)(-700 3850);
WIRE 16 -1 (-400 3800)(-400 3750);
WIRE 16 -1 (-400 3800)(-700 3800);
WIRE 16 -1 (-400 3750)(-400 3700);
WIRE 16 -1 (-400 3750)(-700 3750);
WIRE 16 -1 (-400 3700)(-400 3650);
WIRE 16 -1 (-400 3700)(-700 3700);
WIRE 16 -1 (-400 3650)(-400 3600);
WIRE 16 -1 (-400 3650)(-700 3650);
WIRE 16 -1 (-400 3600)(-400 3550);
WIRE 16 -1 (-400 3600)(-700 3600);
WIRE 16 -1 (-400 3550)(-400 3500);
WIRE 16 -1 (-400 3550)(-700 3550);
WIRE 16 -1 (-400 3500)(-400 3450);
WIRE 16 -1 (-400 3500)(-700 3500);
WIRE 16 -1 (-400 3450)(-400 3400);
WIRE 16 -1 (-400 3450)(-700 3450);
WIRE 16 -1 (-400 3400)(-400 3350);
WIRE 16 -1 (-400 3400)(-700 3400);
WIRE 16 -1 (-400 3350)(-400 3300);
WIRE 16 -1 (-400 3350)(-700 3350);
WIRE 16 -1 (-400 3300)(-400 3250);
WIRE 16 -1 (-400 3300)(-700 3300);
WIRE 16 -1 (-400 3250)(-400 3200);
WIRE 16 -1 (-400 3250)(-700 3250);
WIRE 16 -1 (-400 3200)(-400 3150);
WIRE 16 -1 (-400 3200)(-700 3200);
WIRE 16 -1 (-400 3150)(-400 3100);
WIRE 16 -1 (-400 3150)(-700 3150);
WIRE 16 -1 (-400 3100)(-700 3100);
WIRE 16 -1 (-400 3100)(-400 3050);
WIRE 16 -1 (-400 3050)(-400 3000);
WIRE 16 -1 (-400 3050)(-700 3050);
WIRE 16 -1 (-400 3000)(-400 2950);
WIRE 16 -1 (-400 3000)(-700 3000);
WIRE 16 -1 (-400 2950)(-400 2900);
WIRE 16 -1 (-400 2950)(-700 2950);
WIRE 16 -1 (-400 2900)(-400 2850);
WIRE 16 -1 (-400 2900)(-700 2900);
WIRE 16 -1 (-400 2850)(-400 2800);
WIRE 16 -1 (-400 2850)(-700 2850);
WIRE 16 -1 (-400 2800)(-400 2750);
WIRE 16 -1 (-400 2800)(-700 2800);
WIRE 16 -1 (-400 2750)(-400 2700);
WIRE 16 -1 (-400 2750)(-700 2750);
WIRE 16 -1 (-400 2700)(-400 2650);
WIRE 16 -1 (-400 2700)(-700 2700);
WIRE 16 -1 (-400 2650)(-400 2600);
WIRE 16 -1 (-400 2650)(-700 2650);
WIRE 16 -1 (-400 2600)(-400 2550);
WIRE 16 -1 (-400 2600)(-700 2600);
WIRE 16 -1 (-400 2550)(-400 2500);
WIRE 16 -1 (-400 2550)(-700 2550);
WIRE 16 -1 (-400 2500)(-400 2450);
WIRE 16 -1 (-400 2500)(-700 2500);
WIRE 16 -1 (-400 2450)(-400 2400);
WIRE 16 -1 (-400 2450)(-700 2450);
WIRE 16 -1 (-400 2400)(-400 2350);
WIRE 16 -1 (-400 2400)(-700 2400);
WIRE 16 -1 (-400 2350)(-400 2300);
WIRE 16 -1 (-400 2350)(-700 2350);
WIRE 16 -1 (-400 2300)(-400 2250);
WIRE 16 -1 (-400 2300)(-700 2300);
WIRE 16 -1 (-400 2250)(-400 2200);
WIRE 16 -1 (-400 2250)(-700 2250);
WIRE 16 -1 (-400 2200)(-400 2150);
WIRE 16 -1 (-400 2200)(-700 2200);
WIRE 16 -1 (-400 2150)(-400 2050);
WIRE 16 -1 (-400 2150)(-700 2150);
WIRE 16 -1 (-400 2050)(-400 2000);
WIRE 16 -1 (-400 2050)(-700 2050);
WIRE 16 -1 (-400 2000)(-400 1950);
WIRE 16 -1 (-400 2000)(-700 2000);
WIRE 16 -1 (-400 1950)(-400 1700);
WIRE 16 -1 (-400 1950)(-700 1950);
WIRE 16 -1 (-2200 5200)(-1900 5200);
WIRE 16 -1 (-2200 5250)(-2200 5200);
WIRE 16 -1 (-1900 5250)(-2200 5250);
WIRE 16 -1 (-2200 5250)(-2200 5300);
WIRE 16 -1 (-1900 5300)(-2200 5300);
WIRE 16 -1 (-2200 5300)(-2200 6200);
WIRE 16 -1 (-2325 6200)(-2200 6200);
WIRE 16 -1 (-2325 6200)(-2900 6200);
WIRE 16 -1 (-2325 6200)(-2325 6100);
WIRE 16 -1 (-2900 6200)(-2900 6275);
WIRE 16 -1 (-2900 6100)(-2900 6200);
WIRE 16 -1 (-1900 2050)(-2200 2050);
WIRE 16 -1 (-2200 2100)(-2200 2050);
WIRE 16 -1 (-2200 2050)(-2200 1925);
WIRE 16 -1 (-1900 2100)(-2200 2100);
WIRE 16 -1 (-2200 2150)(-2200 2100);
WIRE 16 -1 (-1900 2150)(-2200 2150);
WIRE 16 -1 (-2200 2200)(-2200 2150);
WIRE 16 -1 (-1900 2200)(-2200 2200);
WIRE 16 -1 (-2200 2250)(-2200 2200);
WIRE 16 -1 (-1900 2250)(-2200 2250);
WIRE 16 -1 (-2200 2300)(-2200 2250);
WIRE 16 -1 (-1900 2300)(-2200 2300);
WIRE 16 -1 (-2200 2350)(-2200 2300);
WIRE 16 -1 (-1900 2350)(-2200 2350);
WIRE 16 -1 (-2200 2400)(-2200 2350);
WIRE 16 -1 (-1900 2400)(-2200 2400);
WIRE 16 -1 (-2200 2450)(-2200 2400);
WIRE 16 -1 (-1900 2450)(-2200 2450);
WIRE 16 -1 (-2200 2500)(-2200 2450);
WIRE 16 -1 (-1900 2500)(-2200 2500);
WIRE 16 -1 (-2200 2550)(-2200 2500);
WIRE 16 -1 (-1900 2550)(-2200 2550);
WIRE 16 -1 (-2200 2600)(-2200 2550);
WIRE 16 -1 (-1900 2600)(-2200 2600);
WIRE 16 -1 (-2200 2650)(-2200 2600);
WIRE 16 -1 (-1900 2650)(-2200 2650);
WIRE 16 -1 (-2200 2700)(-2200 2650);
WIRE 16 -1 (-1900 2700)(-2200 2700);
WIRE 16 -1 (-2200 2750)(-2200 2700);
WIRE 16 -1 (-1900 2750)(-2200 2750);
WIRE 16 -1 (-2200 2800)(-2200 2750);
WIRE 16 -1 (-1900 2800)(-2200 2800);
WIRE 16 -1 (-2200 2850)(-2200 2800);
WIRE 16 -1 (-1900 2850)(-2200 2850);
WIRE 16 -1 (-2200 2900)(-2200 2850);
WIRE 16 -1 (-1900 2900)(-2200 2900);
WIRE 16 -1 (-2200 2950)(-2200 2900);
WIRE 16 -1 (-1900 2950)(-2200 2950);
WIRE 16 -1 (-2200 3000)(-2200 2950);
WIRE 16 -1 (-1900 3000)(-2200 3000);
WIRE 16 -1 (-2200 3050)(-2200 3000);
WIRE 16 -1 (-1900 3050)(-2200 3050);
WIRE 16 -1 (-2200 3100)(-2200 3050);
WIRE 16 -1 (-1900 3100)(-2200 3100);
WIRE 16 -1 (-2200 3150)(-2200 3100);
WIRE 16 -1 (-1900 3150)(-2200 3150);
WIRE 16 -1 (-2200 3200)(-2200 3150);
WIRE 16 -1 (-1900 3200)(-2200 3200);
WIRE 16 -1 (-2200 3250)(-2200 3200);
WIRE 16 -1 (-1900 3250)(-2200 3250);
WIRE 16 -1 (-2200 3300)(-2200 3250);
WIRE 16 -1 (-1900 3300)(-2200 3300);
WIRE 16 -1 (-2200 3350)(-2200 3300);
WIRE 16 -1 (-1900 3350)(-2200 3350);
WIRE 16 -1 (-2200 3400)(-2200 3350);
WIRE 16 -1 (-1900 3400)(-2200 3400);
WIRE 16 -1 (-2200 3450)(-2200 3400);
WIRE 16 -1 (-1900 3450)(-2200 3450);
WIRE 16 -1 (-2200 3500)(-2200 3450);
WIRE 16 -1 (-1900 3500)(-2200 3500);
WIRE 16 -1 (-2200 3550)(-2200 3500);
WIRE 16 -1 (-1900 3550)(-2200 3550);
WIRE 16 -1 (-2200 3600)(-2200 3550);
WIRE 16 -1 (-1900 3600)(-2200 3600);
WIRE 16 -1 (-2200 3650)(-2200 3600);
WIRE 16 -1 (-1900 3650)(-2200 3650);
WIRE 16 -1 (-2200 3700)(-2200 3650);
WIRE 16 -1 (-1900 3700)(-2200 3700);
WIRE 16 -1 (-2200 3750)(-2200 3700);
WIRE 16 -1 (-1900 3750)(-2200 3750);
WIRE 16 -1 (-2200 3800)(-2200 3750);
WIRE 16 -1 (-1900 3800)(-2200 3800);
WIRE 16 -1 (-2200 3850)(-2200 3800);
WIRE 16 -1 (-1900 3850)(-2200 3850);
WIRE 16 -1 (-2200 3900)(-2200 3850);
WIRE 16 -1 (-1900 3900)(-2200 3900);
WIRE 16 -1 (-2200 3950)(-2200 3900);
WIRE 16 -1 (-1900 3950)(-2200 3950);
WIRE 16 -1 (-2200 4000)(-2200 3950);
WIRE 16 -1 (-1900 4000)(-2200 4000);
WIRE 16 -1 (-2200 4050)(-2200 4000);
WIRE 16 -1 (-2200 4100)(-2200 4050);
WIRE 16 -1 (-1900 4050)(-2200 4050);
WIRE 16 -1 (-1900 4100)(-2200 4100);
WIRE 16 -1 (-2200 4150)(-2200 4100);
WIRE 16 -1 (-1900 4150)(-2200 4150);
WIRE 16 -1 (-2200 4200)(-2200 4150);
WIRE 16 -1 (-1900 4200)(-2200 4200);
WIRE 16 -1 (-2200 4250)(-2200 4200);
WIRE 16 -1 (-1900 4250)(-2200 4250);
WIRE 16 -1 (-2200 4300)(-2200 4250);
WIRE 16 -1 (-1900 4300)(-2200 4300);
WIRE 16 -1 (-2200 4350)(-2200 4300);
WIRE 16 -1 (-1900 4350)(-2200 4350);
WIRE 16 -1 (-2200 4400)(-2200 4350);
WIRE 16 -1 (-1900 4400)(-2200 4400);
WIRE 16 -1 (-2200 4450)(-2200 4400);
WIRE 16 -1 (-1900 4450)(-2200 4450);
WIRE 16 -1 (-2200 4500)(-2200 4450);
WIRE 16 -1 (-1900 4500)(-2200 4500);
WIRE 16 -1 (-2200 4550)(-2200 4500);
WIRE 16 -1 (-1900 4550)(-2200 4550);
WIRE 16 -1 (-2200 4600)(-2200 4550);
WIRE 16 -1 (-1900 4600)(-2200 4600);
WIRE 16 -1 (-2200 4650)(-2200 4600);
WIRE 16 -1 (-1900 4650)(-2200 4650);
WIRE 16 -1 (-2200 4700)(-2200 4650);
WIRE 16 -1 (-1900 4700)(-2200 4700);
WIRE 16 -1 (-2200 4750)(-2200 4700);
WIRE 16 -1 (-1900 4750)(-2200 4750);
WIRE 16 -1 (-2200 4800)(-2200 4750);
WIRE 16 -1 (-1900 4800)(-2200 4800);
WIRE 16 -1 (-2200 4850)(-2200 4800);
WIRE 16 -1 (-1900 4850)(-2200 4850);
WIRE 16 -1 (-2200 4900)(-2200 4850);
WIRE 16 -1 (-1900 4900)(-2200 4900);
WIRE 16 -1 (-2200 4950)(-2200 4900);
WIRE 16 -1 (-1900 4950)(-2200 4950);
WIRE 16 -1 (-2200 5000)(-2200 4950);
WIRE 16 -1 (-1900 5000)(-2200 5000);
WIRE 16 -1 (-2200 5050)(-2200 5000);
WIRE 16 -1 (-1900 5050)(-2200 5050);
WIRE 16 -1 (-2200 5100)(-2200 5050);
WIRE 16 -1 (-1900 5100)(-2200 5100);
WIRE 16 -1 (-2200 5150)(-2200 5100);
WIRE 16 -1 (-1900 5150)(-2200 5150);
WIRE 16 -1 (-3700 3300)(-3550 3300);
WIRE 16 -1 (-3700 3250)(-3350 3250);
WIRE 16 -1 (-3700 4350)(-3550 4350);
WIRE 16 -1 (-3700 4300)(-3350 4300);
WIRE 16 -1 (-3550 4250)(-3700 4250);
WIRE 16 -1 (-3700 4200)(-3350 4200);
WIRE 16 -1 (-3700 3050)(-3350 3050);
WIRE 16 -1 (-3550 4150)(-3700 4150);
WIRE 16 -1 (-3550 3000)(-3700 3000);
WIRE 16 -1 (-3350 2950)(-3700 2950);
WIRE 16 -1 (-3700 4000)(-3350 4000);
WIRE 16 -1 (-3700 2900)(-3550 2900);
WIRE 16 -1 (-3700 2850)(-3350 2850);
WIRE 16 -1 (-3700 3950)(-3550 3950);
WIRE 16 -1 (-3700 3900)(-3350 3900);
WIRE 16 -1 (-3550 2800)(-3700 2800);
WIRE 16 -1 (-3700 2750)(-3350 2750);
WIRE 16 -1 (-3550 3850)(-3700 3850);
WIRE 16 -1 (-3700 3800)(-3350 3800);
WIRE 16 -1 (-3550 2700)(-3700 2700);
WIRE 16 -1 (-3700 2650)(-3350 2650);
WIRE 16 -1 (-3550 3750)(-3700 3750);
WIRE 16 -1 (-3700 3700)(-3350 3700);
WIRE 16 -1 (-3550 2600)(-3700 2600);
WIRE 16 -1 (-3700 2550)(-3350 2550);
WIRE 16 -1 (-3550 3650)(-3700 3650);
WIRE 16 -1 (-3700 3600)(-3350 3600);
WIRE 16 -1 (-3700 2500)(-3550 2500);
WIRE 16 -1 (-3700 2450)(-3350 2450);
WIRE 16 -1 (-3700 3550)(-3550 3550);
WIRE 16 -1 (-3700 3500)(-3350 3500);
WIRE 16 -1 (-3550 2400)(-3700 2400);
WIRE 16 -1 (-3700 2350)(-3350 2350);
WIRE 16 -1 (-3550 3450)(-3700 3450);
WIRE 16 -1 (-3700 3400)(-3350 3400);
WIRE 16 -1 (-3550 3100)(-3700 3100);
WIRE 16 -1 (-3700 3150)(-3350 3150);
WIRE 16 -1 (-3550 3200)(-3700 3200);
WIRE 16 -1 (-3550 4050)(-3700 4050);
WIRE 16 -1 (-3700 4100)(-3350 4100);
WIRE 16 -1 (-6275 5350)(-6075 5350);
WIRE 16 -1 (-7475 2250)(-8100 2250);
FORCEPROP 2 LAST SIG_NAME TP_CHH_CPU0_DIMM_RFU_3
J 0
(-8110 2260);
DISPLAY 0.489362 (-8110 2260);
FORCEPROP 2 LASTPROP $XRERR UNIQUE?
J 0
(-8340 2250);
DISPLAY 0.638298 (-8340 2250);
PAINT MONO (-8340 2250);
DISPLAY INVISIBLE (-8340 2250);
WIRE 16 -1 (-7475 2300)(-8100 2300);
FORCEPROP 2 LAST SIG_NAME TP_CHH_CPU0_DIMM_RFU_4
J 0
(-8110 2310);
DISPLAY 0.489362 (-8110 2310);
FORCEPROP 2 LASTPROP $XRERR UNIQUE?
J 0
(-8340 2300);
DISPLAY 0.638298 (-8340 2300);
PAINT MONO (-8340 2300);
DISPLAY INVISIBLE (-8340 2300);
WIRE 16 -1 (-7475 3050)(-8125 3050);
FORCEPROP 2 LAST SIG_NAME M_H_CPU0_RESET_N
J 0
(-8110 3060);
DISPLAY 0.489362 (-8110 3060);
WIRE 16 -1 (-7475 4500)(-8275 4500);
FORCEPROP 2 LAST SIG_NAME M_H_CPU0_SB_PAR
J 0
(-8225 4510);
DISPLAY 0.489362 (-8225 4510);
WIRE 16 -1 (-7475 4550)(-8275 4550);
FORCEPROP 2 LAST SIG_NAME M_H_CPU0_SA_PAR
J 0
(-8225 4560);
DISPLAY 0.489362 (-8225 4560);
WIRE 16 -1 (-7475 1900)(-8275 1900);
FORCEPROP 2 LAST SIG_NAME M_H_CPU0_SB_RSP<0>
J 0
(-8225 1910);
DISPLAY 0.489362 (-8225 1910);
WIRE 16 -1 (-7475 1950)(-8275 1950);
FORCEPROP 2 LAST SIG_NAME M_H_CPU0_SA_RSP<0>
J 0
(-8225 1960);
DISPLAY 0.489362 (-8225 1960);
WIRE 16 -1 (-6075 2150)(-6275 2150);
WIRE 16 -1 (-6075 2200)(-6275 2200);
WIRE 16 -1 (-6075 2250)(-6275 2250);
WIRE 16 -1 (-6275 2300)(-6075 2300);
WIRE 16 -1 (-6075 2350)(-6275 2350);
WIRE 16 -1 (-6075 2400)(-6275 2400);
WIRE 16 -1 (-6075 2450)(-6275 2450);
WIRE 16 -1 (-6275 2500)(-6075 2500);
WIRE 16 -1 (-6075 2550)(-6275 2550);
WIRE 16 -1 (-6075 2600)(-6275 2600);
WIRE 16 -1 (-6075 2650)(-6275 2650);
WIRE 16 -1 (-6275 2700)(-6075 2700);
WIRE 16 -1 (-6075 2750)(-6275 2750);
WIRE 16 -1 (-6075 2800)(-6275 2800);
WIRE 16 -1 (-6075 2850)(-6275 2850);
WIRE 16 -1 (-6275 2900)(-6075 2900);
WIRE 16 -1 (-6075 2950)(-6275 2950);
WIRE 16 -1 (-6075 3000)(-6275 3000);
WIRE 16 -1 (-6075 3050)(-6275 3050);
WIRE 16 -1 (-6275 3100)(-6075 3100);
WIRE 16 -1 (-6075 3150)(-6275 3150);
WIRE 16 -1 (-6075 3200)(-6275 3200);
WIRE 16 -1 (-6075 3250)(-6275 3250);
WIRE 16 -1 (-6275 3300)(-6075 3300);
WIRE 16 -1 (-6075 3350)(-6275 3350);
WIRE 16 -1 (-6075 3400)(-6275 3400);
WIRE 16 -1 (-6075 3450)(-6275 3450);
WIRE 16 -1 (-6275 3500)(-6075 3500);
WIRE 16 -1 (-6075 3550)(-6275 3550);
WIRE 16 -1 (-6075 3600)(-6275 3600);
WIRE 16 -1 (-6075 3650)(-6275 3650);
WIRE 16 -1 (-6275 3700)(-6075 3700);
WIRE 16 -1 (-6075 3800)(-6275 3800);
WIRE 16 -1 (-6075 3850)(-6275 3850);
WIRE 16 -1 (-6075 3900)(-6275 3900);
WIRE 16 -1 (-6275 3950)(-6075 3950);
WIRE 16 -1 (-6075 4000)(-6275 4000);
WIRE 16 -1 (-6075 4050)(-6275 4050);
WIRE 16 -1 (-6075 4100)(-6275 4100);
WIRE 16 -1 (-6275 4150)(-6075 4150);
WIRE 16 -1 (-6075 4200)(-6275 4200);
WIRE 16 -1 (-6075 4250)(-6275 4250);
WIRE 16 -1 (-6075 4300)(-6275 4300);
WIRE 16 -1 (-6275 4350)(-6075 4350);
WIRE 16 -1 (-6075 4400)(-6275 4400);
WIRE 16 -1 (-6075 4450)(-6275 4450);
WIRE 16 -1 (-6075 4500)(-6275 4500);
WIRE 16 -1 (-6275 4550)(-6075 4550);
WIRE 16 -1 (-6075 4600)(-6275 4600);
WIRE 16 -1 (-6075 4650)(-6275 4650);
WIRE 16 -1 (-6075 4700)(-6275 4700);
WIRE 16 -1 (-6275 4750)(-6075 4750);
WIRE 16 -1 (-6075 4800)(-6275 4800);
WIRE 16 -1 (-6075 4850)(-6275 4850);
WIRE 16 -1 (-6075 4900)(-6275 4900);
WIRE 16 -1 (-6275 4950)(-6075 4950);
WIRE 16 -1 (-6075 5000)(-6275 5000);
WIRE 16 -1 (-6075 5050)(-6275 5050);
WIRE 16 -1 (-6075 5100)(-6275 5100);
WIRE 16 -1 (-6275 5150)(-6075 5150);
WIRE 16 -1 (-6075 5200)(-6275 5200);
WIRE 16 -1 (-6075 5250)(-6275 5250);
WIRE 16 -1 (-6075 5300)(-6275 5300);
WIRE 16 -1 (-7475 4250)(-8275 4250);
FORCEPROP 2 LAST SIG_NAME M_H_CPU0_SB_CS_N<1>
J 0
(-8225 4260);
DISPLAY 0.489362 (-8225 4260);
WIRE 16 -1 (-7475 4400)(-8275 4400);
FORCEPROP 2 LAST SIG_NAME M_H_CPU0_SA_CS_N<1>
J 0
(-8225 4410);
DISPLAY 0.489362 (-8225 4410);
WIRE 16 -1 (-7475 4200)(-8275 4200);
FORCEPROP 2 LAST SIG_NAME M_H_CPU0_SB_CS_N<0>
J 0
(-8225 4210);
DISPLAY 0.489362 (-8225 4210);
WIRE 16 -1 (-7475 4350)(-8275 4350);
FORCEPROP 2 LAST SIG_NAME M_H_CPU0_SA_CS_N<0>
J 0
(-8225 4360);
DISPLAY 0.489362 (-8225 4360);
WIRE 16 -1 (-7475 4100)(-8275 4100);
FORCEPROP 2 LAST SIG_NAME M_H_CPU0_CLK_DP<0>
J 0
(-8225 4110);
DISPLAY 0.489362 (-8225 4110);
WIRE 16 -1 (-7475 4050)(-8275 4050);
FORCEPROP 2 LAST SIG_NAME M_H_CPU0_CLK_DN<0>
J 0
(-8225 4060);
DISPLAY 0.489362 (-8225 4060);
WIRE 16 -1 (-7475 3150)(-7675 3150);
WIRE 16 -1 (-7475 3200)(-7675 3200);
WIRE 16 -1 (-7475 3250)(-7675 3250);
WIRE 16 -1 (-7475 3300)(-7675 3300);
WIRE 16 -1 (-7475 3350)(-7675 3350);
WIRE 16 -1 (-7475 3400)(-7675 3400);
WIRE 16 -1 (-7475 3450)(-7675 3450);
WIRE 16 -1 (-7475 3600)(-7675 3600);
WIRE 16 -1 (-7475 3700)(-7675 3700);
WIRE 16 -1 (-7475 3750)(-7675 3750);
WIRE 16 -1 (-7475 3850)(-7675 3850);
WIRE 16 -1 (-7475 3900)(-7675 3900);
WIRE 16 -1 (-7475 4950)(-7675 4950);
WIRE 16 -1 (-7475 4900)(-7675 4900);
WIRE 16 -1 (-7475 4850)(-7675 4850);
WIRE 16 -1 (-7475 4800)(-7675 4800);
WIRE 16 -1 (-7475 5200)(-7675 5200);
WIRE 16 -1 (-7475 4750)(-7675 4750);
WIRE 16 -1 (-7475 5150)(-7675 5150);
WIRE 16 -1 (-7475 4700)(-7675 4700);
WIRE 16 -1 (-7475 5100)(-7675 5100);
WIRE 16 -1 (-7475 4650)(-7675 4650);
WIRE 16 -1 (-7475 5050)(-7675 5050);
WIRE 16 -1 (-7475 3000)(-8125 3000);
FORCEPROP 2 LAST SIG_NAME M_H_CPU0_ALERT_N
J 0
(-8110 3010);
DISPLAY 0.489362 (-8110 3010);
WIRE 16 -1 (-7475 3500)(-7675 3500);
WIRE 16 -1 (-7475 3650)(-7675 3650);
WIRE 16 -1 (-7475 3800)(-7675 3800);
WIRE 16 -1 (-7475 3950)(-7675 3950);
WIRE 16 -1 (-9025 2100)(-8625 2100);
FORCEPROP 2 LAST SIG_NAME PWRGD_CHGL_CPU0
J 0
(-9010 2110);
DISPLAY 0.489362 (-9010 2110);
WIRE 16 -1 (-6425 1350)(-6425 1275);
WIRE 16 -1 (-6425 1350)(-7150 1350);
FORCEPROP 2 LAST SIG_NAME PD_CHH_CPU0_DIMM_SAA
J 0
(-7135 1360);
DISPLAY 0.489362 (-7135 1360);
WIRE 16 -1 (-2325 5775)(-2900 5775);
WIRE 16 -1 (-2325 5775)(-2325 5900);
WIRE 16 -1 (-2900 5775)(-2900 5900);
WIRE 16 -1 (-2900 5775)(-2900 5700);
DOT 1 (-2900 6200);
DOT 1 (-2325 6200);
DOT 1 (-2900 5775);
DOT 1 (-400 5050);
DOT 1 (-400 4950);
DOT 1 (-8400 2100);
DOT 1 (-8550 3300);
DOT 1 (-2200 2050);
DOT 1 (-2200 2200);
DOT 1 (-2200 2150);
DOT 1 (-2200 2100);
DOT 1 (-2200 2300);
DOT 1 (-2200 2250);
DOT 1 (-2200 2450);
DOT 1 (-2200 2400);
DOT 1 (-2200 2350);
DOT 1 (-2200 2550);
DOT 1 (-2200 2500);
DOT 1 (-2200 2600);
DOT 1 (-2200 2750);
DOT 1 (-2200 2700);
DOT 1 (-2200 2650);
DOT 1 (-2200 2800);
DOT 1 (-2200 3000);
DOT 1 (-2200 2900);
DOT 1 (-2200 3050);
DOT 1 (-2200 3100);
DOT 1 (-2200 2950);
DOT 1 (-2200 3200);
DOT 1 (-2200 3250);
DOT 1 (-2200 3150);
DOT 1 (-2200 3350);
DOT 1 (-2200 3300);
DOT 1 (-2200 3450);
DOT 1 (-2200 3500);
DOT 1 (-2200 3400);
DOT 1 (-2200 3600);
DOT 1 (-2200 3550);
DOT 1 (-2200 3700);
DOT 1 (-2200 3750);
DOT 1 (-2200 3650);
DOT 1 (-2200 3850);
DOT 1 (-2200 3800);
DOT 1 (-400 2050);
DOT 1 (-400 1950);
DOT 1 (-400 2000);
DOT 1 (-400 2300);
DOT 1 (-400 2250);
DOT 1 (-400 2200);
DOT 1 (-400 2150);
DOT 1 (-400 2450);
DOT 1 (-400 2400);
DOT 1 (-400 2350);
DOT 1 (-400 2550);
DOT 1 (-400 2500);
DOT 1 (-400 2600);
DOT 1 (-400 2750);
DOT 1 (-400 2700);
DOT 1 (-400 2650);
DOT 1 (-400 2800);
DOT 1 (-400 2850);
DOT 1 (-400 3000);
DOT 1 (-400 2900);
DOT 1 (-400 3050);
DOT 1 (-400 3100);
DOT 1 (-400 2950);
DOT 1 (-400 3200);
DOT 1 (-400 3250);
DOT 1 (-400 3150);
DOT 1 (-400 3350);
DOT 1 (-400 3300);
DOT 1 (-400 3500);
DOT 1 (-400 3450);
DOT 1 (-400 3400);
DOT 1 (-400 3600);
DOT 1 (-400 3550);
DOT 1 (-400 3750);
DOT 1 (-400 3700);
DOT 1 (-400 3650);
DOT 1 (-400 3850);
DOT 1 (-400 3800);
DOT 1 (-2200 4000);
DOT 1 (-2200 3950);
DOT 1 (-2200 3900);
DOT 1 (-2200 4100);
DOT 1 (-2200 4050);
DOT 1 (-2200 4250);
DOT 1 (-2200 4150);
DOT 1 (-2200 4300);
DOT 1 (-2200 4450);
DOT 1 (-2200 4500);
DOT 1 (-2200 4400);
DOT 1 (-2200 4600);
DOT 1 (-2200 4550);
DOT 1 (-2200 4650);
DOT 1 (-2200 4800);
DOT 1 (-2200 4750);
DOT 1 (-2200 4700);
DOT 1 (-2200 4850);
DOT 1 (-2200 4900);
DOT 1 (-2200 5000);
DOT 1 (-2200 4950);
DOT 1 (-2200 5100);
DOT 1 (-2200 5050);
DOT 1 (-2200 5250);
DOT 1 (-2200 5300);
DOT 1 (-400 4000);
DOT 1 (-400 3950);
DOT 1 (-400 3900);
DOT 1 (-400 4100);
DOT 1 (-400 4050);
DOT 1 (-400 4250);
DOT 1 (-400 4200);
DOT 1 (-400 4150);
DOT 1 (-400 4350);
DOT 1 (-400 4300);
DOT 1 (-400 4450);
DOT 1 (-400 4500);
DOT 1 (-400 4400);
DOT 1 (-400 4600);
DOT 1 (-400 4550);
DOT 1 (-400 4650);
DOT 1 (-400 4750);
DOT 1 (-400 4700);
DOT 1 (-400 4850);
DOT 1 (-400 4900);
DOT 1 (-400 5000);
DOT 1 (-400 5100);
DOT 1 (-400 5150);
DOT 1 (-400 5200);
DOT 1 (-400 5250);
DOT 1 (-2200 2850);
DOT 1 (-2200 4350);
DOT 1 (-400 4800);
DOT 1 (-2200 4200);
QUIT
